FILE_TYPE = MACRO_DRAWING;
SET COLOR_WIRE YELLOW;
SET COLOR_PROP MONO;
SET COLOR_DOT WHITE;
SET COLOR_ARC YELLOW;
SET COLOR_BODY GREEN;
SET COLOR_NOTE MONO;
SET PROP_DISPLAY VALUE;
SET PAGE_NUMBER P192;
FORCEADD CAP_A..1
(-1225 1975);
FORCEPROP 1 LAST LOCATION C2P8
J 0
(-1175 2075);
DISPLAY 0.617021 (-1175 2075);
PAINT AQUA (-1175 2075);
FORCEPROP 1 LAST PART_NUMBER A36096-045
J 0
(-1175 1825);
DISPLAY 0.617021 (-1175 1825);
PAINT BLUE (-1175 1825);
FORCEPROP 1 LAST VALUE 0.01UF
J 0
(-1175 2025);
DISPLAY 0.617021 (-1175 2025);
PAINT SKYBLUE (-1175 2025);
FORCEPROP 1 LAST TOLERANCE 10%
J 0
(-1175 1925);
DISPLAY 0.617021 (-1175 1925);
PAINT SKYBLUE (-1175 1925);
FORCEPROP 1 LAST PACK_TYPE 0402V
J 0
(-1175 1775);
DISPLAY 0.617021 (-1175 1775);
PAINT SKYBLUE (-1175 1775);
FORCEPROP 1 LAST VOLTAGE 25V
J 0
(-1175 1975);
DISPLAY 0.617021 (-1175 1975);
PAINT SKYBLUE (-1175 1975);
FORCEPROP 1 LAST MATERIAL X7R
J 0
(-1175 1875);
DISPLAY 0.617021 (-1175 1875);
PAINT SKYBLUE (-1175 1875);
FORCEPROP 1 LASTPIN (-1225 2075) $PN 1
J 0
(-1215 2055);
DISPLAY 0.617021 (-1215 2055);
PAINT ORANGE (-1215 2055);
FORCEPROP 1 LASTPIN (-1225 1875) $PN 2
J 0
(-1215 1855);
DISPLAY 0.617021 (-1215 1855);
PAINT ORANGE (-1215 1855);
FORCEPROP 2 LAST ROOM CPLD
J 0
(-1175 2125);
DISPLAY 1.361702 (-1175 2125);
PAINT ORANGE (-1175 2125);
DISPLAY INVISIBLE (-1175 2125);
FORCEPROP 2 LAST CDS_LOCATION C2P8
J 0
(-1175 2075);
DISPLAY 0.617021 (-1175 2075);
PAINT AQUA (-1175 2075);
DISPLAY INVISIBLE (-1175 2075);
FORCEPROP 2 LAST BOM_COST CPLD
J 0
(-1175 2175);
DISPLAY 1.361702 (-1175 2175);
PAINT ORANGE (-1175 2175);
DISPLAY INVISIBLE (-1175 2175);
FORCEPROP 2 LAST SIGNAL_MODEL DEFAULT_CAPACITOR_10000pF_2_1
J 0
(-1175 2175);
PAINT MONO (-1175 2175);
DISPLAY INVISIBLE (-1175 2175);
FORCEPROP 2 LAST CDS_SEC 1
J 0
(-1175 2175);
PAINT MONO (-1175 2175);
DISPLAY INVISIBLE (-1175 2175);
FORCEPROP 2 LAST $SEC 1
J 0
(-1175 2175);
PAINT MONO (-1175 2175);
DISPLAY INVISIBLE (-1175 2175);
FORCEPROP 1 LAST PATH I1
J 0
(-1175 2125);
DISPLAY 0.978723 (-1175 2125);
PAINT WHITE (-1175 2125);
DISPLAY INVISIBLE (-1175 2125);
FORCEPROP 2 LAST CDS_LIB dev_discrete
J 0
(-1225 1975);
PAINT ORANGE (-1225 1975);
DISPLAY INVISIBLE (-1225 1975);
FORCEADD CAP_A..1
(-4075 1975);
FORCEPROP 1 LAST LOCATION C3R2
J 0
(-4025 2075);
DISPLAY 0.617021 (-4025 2075);
PAINT AQUA (-4025 2075);
FORCEPROP 1 LAST PART_NUMBER A36096-030
J 0
(-4025 1825);
DISPLAY 0.617021 (-4025 1825);
PAINT BLUE (-4025 1825);
FORCEPROP 1 LAST VALUE 0.1UF
J 0
(-4025 2025);
DISPLAY 0.617021 (-4025 2025);
PAINT SKYBLUE (-4025 2025);
FORCEPROP 1 LAST TOLERANCE 10%
J 0
(-4025 1925);
DISPLAY 0.617021 (-4025 1925);
PAINT SKYBLUE (-4025 1925);
FORCEPROP 1 LAST PACK_TYPE 0402V
J 0
(-4025 1775);
DISPLAY 0.617021 (-4025 1775);
PAINT SKYBLUE (-4025 1775);
FORCEPROP 1 LAST VOLTAGE 16V
J 0
(-4025 1975);
DISPLAY 0.617021 (-4025 1975);
PAINT SKYBLUE (-4025 1975);
FORCEPROP 1 LAST MATERIAL X7R
J 0
(-4025 1875);
DISPLAY 0.617021 (-4025 1875);
PAINT SKYBLUE (-4025 1875);
FORCEPROP 1 LASTPIN (-4075 2075) $PN 1
J 0
(-4065 2055);
DISPLAY 0.617021 (-4065 2055);
PAINT ORANGE (-4065 2055);
FORCEPROP 1 LASTPIN (-4075 1875) $PN 2
J 0
(-4065 1855);
DISPLAY 0.617021 (-4065 1855);
PAINT ORANGE (-4065 1855);
FORCEPROP 2 LAST ROOM CPLD
J 0
(-4025 2125);
DISPLAY 1.361702 (-4025 2125);
PAINT ORANGE (-4025 2125);
DISPLAY INVISIBLE (-4025 2125);
FORCEPROP 2 LAST SIGNAL_MODEL DEFAULT_CAPACITOR_100000pF_2_1
J 0
(-4025 2175);
PAINT MONO (-4025 2175);
DISPLAY INVISIBLE (-4025 2175);
FORCEPROP 2 LAST BOM_COST CPLD
J 0
(-4025 2175);
DISPLAY 1.361702 (-4025 2175);
PAINT ORANGE (-4025 2175);
DISPLAY INVISIBLE (-4025 2175);
FORCEPROP 2 LAST CDS_SEC 1
J 0
(-4025 2175);
PAINT MONO (-4025 2175);
DISPLAY INVISIBLE (-4025 2175);
FORCEPROP 2 LAST $SEC 1
J 0
(-4025 2175);
PAINT MONO (-4025 2175);
DISPLAY INVISIBLE (-4025 2175);
FORCEPROP 1 LAST PATH I10
J 0
(-4025 2125);
DISPLAY 0.978723 (-4025 2125);
PAINT WHITE (-4025 2125);
DISPLAY INVISIBLE (-4025 2125);
FORCEPROP 2 LAST CDS_LOCATION C3R2
J 0
(-4025 2075);
DISPLAY 0.617021 (-4025 2075);
PAINT AQUA (-4025 2075);
DISPLAY INVISIBLE (-4025 2075);
FORCEPROP 2 LAST CDS_LIB dev_discrete
J 0
(-4075 1975);
PAINT ORANGE (-4075 1975);
DISPLAY INVISIBLE (-4075 1975);
FORCEADD CAP_A..1
(-3700 1300);
FORCEPROP 1 LAST LOCATION C3P51
J 0
(-3650 1400);
DISPLAY 0.617021 (-3650 1400);
PAINT AQUA (-3650 1400);
FORCEPROP 1 LAST PART_NUMBER A36096-030
J 0
(-3650 1150);
DISPLAY 0.617021 (-3650 1150);
PAINT BLUE (-3650 1150);
FORCEPROP 1 LAST VALUE 0.1UF
J 0
(-3650 1350);
DISPLAY 0.617021 (-3650 1350);
PAINT SKYBLUE (-3650 1350);
FORCEPROP 1 LAST TOLERANCE 10%
J 0
(-3650 1250);
DISPLAY 0.617021 (-3650 1250);
PAINT SKYBLUE (-3650 1250);
FORCEPROP 1 LAST PACK_TYPE 0402V
J 0
(-3650 1100);
DISPLAY 0.617021 (-3650 1100);
PAINT SKYBLUE (-3650 1100);
FORCEPROP 1 LAST VOLTAGE 16V
J 0
(-3650 1300);
DISPLAY 0.617021 (-3650 1300);
PAINT SKYBLUE (-3650 1300);
FORCEPROP 1 LAST MATERIAL X7R
J 0
(-3650 1200);
DISPLAY 0.617021 (-3650 1200);
PAINT SKYBLUE (-3650 1200);
FORCEPROP 1 LASTPIN (-3700 1400) $PN 1
J 0
(-3690 1380);
DISPLAY 0.617021 (-3690 1380);
PAINT ORANGE (-3690 1380);
FORCEPROP 1 LASTPIN (-3700 1200) $PN 2
J 0
(-3690 1180);
DISPLAY 0.617021 (-3690 1180);
PAINT ORANGE (-3690 1180);
FORCEPROP 2 LAST ROOM CPLD
J 0
(-3650 1450);
DISPLAY 1.361702 (-3650 1450);
PAINT ORANGE (-3650 1450);
DISPLAY INVISIBLE (-3650 1450);
FORCEPROP 2 LAST $SEC 1
J 0
(-3650 1500);
DISPLAY 0.914894 (-3650 1500);
PAINT MONO (-3650 1500);
DISPLAY INVISIBLE (-3650 1500);
FORCEPROP 2 LAST CDS_SEC 1
J 0
(-3650 1500);
DISPLAY 1.361702 (-3650 1500);
PAINT ORANGE (-3650 1500);
DISPLAY INVISIBLE (-3650 1500);
FORCEPROP 2 LAST BOM_COST CPLD
J 0
(-3650 1500);
DISPLAY 1.361702 (-3650 1500);
PAINT ORANGE (-3650 1500);
DISPLAY INVISIBLE (-3650 1500);
FORCEPROP 2 LAST SIGNAL_MODEL DEFAULT_CAPACITOR_100000pF_2_1
J 0
(-3650 1500);
PAINT MONO (-3650 1500);
DISPLAY INVISIBLE (-3650 1500);
FORCEPROP 1 LAST PATH I11
J 0
(-3650 1450);
DISPLAY 0.978723 (-3650 1450);
PAINT WHITE (-3650 1450);
DISPLAY INVISIBLE (-3650 1450);
FORCEPROP 2 LAST CDS_LOCATION C3P51
J 0
(-3650 1400);
DISPLAY 0.617021 (-3650 1400);
PAINT AQUA (-3650 1400);
DISPLAY INVISIBLE (-3650 1400);
FORCEPROP 2 LAST CDS_LIB dev_discrete
J 0
(-3700 1300);
PAINT ORANGE (-3700 1300);
DISPLAY INVISIBLE (-3700 1300);
FORCEADD CAP_A..1
(-4200 1300);
FORCEPROP 1 LAST LOCATION C3P47
J 0
(-4150 1400);
DISPLAY 0.617021 (-4150 1400);
PAINT AQUA (-4150 1400);
FORCEPROP 1 LAST PART_NUMBER A36096-030
J 0
(-4150 1150);
DISPLAY 0.617021 (-4150 1150);
PAINT BLUE (-4150 1150);
FORCEPROP 1 LAST VALUE 0.1UF
J 0
(-4150 1350);
DISPLAY 0.617021 (-4150 1350);
PAINT SKYBLUE (-4150 1350);
FORCEPROP 1 LAST TOLERANCE 10%
J 0
(-4150 1250);
DISPLAY 0.617021 (-4150 1250);
PAINT SKYBLUE (-4150 1250);
FORCEPROP 1 LAST PACK_TYPE 0402V
J 0
(-4150 1100);
DISPLAY 0.617021 (-4150 1100);
PAINT SKYBLUE (-4150 1100);
FORCEPROP 1 LAST VOLTAGE 16V
J 0
(-4150 1300);
DISPLAY 0.617021 (-4150 1300);
PAINT SKYBLUE (-4150 1300);
FORCEPROP 1 LAST MATERIAL X7R
J 0
(-4150 1200);
DISPLAY 0.617021 (-4150 1200);
PAINT SKYBLUE (-4150 1200);
FORCEPROP 1 LASTPIN (-4200 1400) $PN 1
J 0
(-4190 1380);
DISPLAY 0.617021 (-4190 1380);
PAINT ORANGE (-4190 1380);
FORCEPROP 1 LASTPIN (-4200 1200) $PN 2
J 0
(-4190 1180);
DISPLAY 0.617021 (-4190 1180);
PAINT ORANGE (-4190 1180);
FORCEPROP 2 LAST ROOM CPLD
J 0
(-4150 1450);
DISPLAY 1.361702 (-4150 1450);
PAINT ORANGE (-4150 1450);
DISPLAY INVISIBLE (-4150 1450);
FORCEPROP 2 LAST $SEC 1
J 0
(-4150 1500);
DISPLAY 0.914894 (-4150 1500);
PAINT MONO (-4150 1500);
DISPLAY INVISIBLE (-4150 1500);
FORCEPROP 2 LAST CDS_SEC 1
J 0
(-4150 1500);
DISPLAY 1.361702 (-4150 1500);
PAINT ORANGE (-4150 1500);
DISPLAY INVISIBLE (-4150 1500);
FORCEPROP 2 LAST BOM_COST CPLD
J 0
(-4150 1500);
DISPLAY 1.361702 (-4150 1500);
PAINT ORANGE (-4150 1500);
DISPLAY INVISIBLE (-4150 1500);
FORCEPROP 2 LAST SIGNAL_MODEL DEFAULT_CAPACITOR_100000pF_2_1
J 0
(-4150 1500);
PAINT MONO (-4150 1500);
DISPLAY INVISIBLE (-4150 1500);
FORCEPROP 1 LAST PATH I12
J 0
(-4150 1450);
DISPLAY 0.978723 (-4150 1450);
PAINT WHITE (-4150 1450);
DISPLAY INVISIBLE (-4150 1450);
FORCEPROP 2 LAST CDS_LOCATION C3P47
J 0
(-4150 1400);
DISPLAY 0.617021 (-4150 1400);
PAINT AQUA (-4150 1400);
DISPLAY INVISIBLE (-4150 1400);
FORCEPROP 2 LAST CDS_LIB dev_discrete
J 0
(-4200 1300);
PAINT ORANGE (-4200 1300);
DISPLAY INVISIBLE (-4200 1300);
FORCEADD LCMXO2_A..6
(-1850 3900);
FORCEPROP 1 LAST LOCATION U8D7
J 0
(-2274 4726);
DISPLAY 0.617021 (-2274 4726);
PAINT AQUA (-2274 4726);
FORCEPROP 1 LAST PART_NUMBER H63395-001
J 0
(-2250 3100);
DISPLAY 0.617021 (-2250 3100);
PAINT BLUE (-2250 3100);
FORCEPROP 1 LAST MATERIAL IC
J 0
(-2275 4675);
DISPLAY 0.617021 (-2275 4675);
PAINT SKYBLUE (-2275 4675);
FORCEPROP 2 LASTPIN (-2300 3900) $PN M4
J 2
(-2310 3910);
DISPLAY 0.617021 (-2310 3910);
PAINT ORANGE (-2310 3910);
FORCEPROP 2 LASTPIN (-2300 3450) $PN D5
J 2
(-2310 3460);
DISPLAY 0.617021 (-2310 3460);
PAINT ORANGE (-2310 3460);
FORCEPROP 2 LASTPIN (-2300 4050) $PN E4
J 2
(-2310 4060);
DISPLAY 0.617021 (-2310 4060);
PAINT ORANGE (-2310 4060);
FORCEPROP 2 LASTPIN (-2300 4000) $PN H7
J 2
(-2310 4010);
DISPLAY 0.617021 (-2310 4010);
PAINT ORANGE (-2310 4010);
FORCEPROP 2 LASTPIN (-2300 3950) $PN J7
J 2
(-2310 3960);
DISPLAY 0.617021 (-2310 3960);
PAINT ORANGE (-2310 3960);
FORCEPROP 2 LASTPIN (-2300 3850) $PN N5
J 2
(-2310 3860);
DISPLAY 0.617021 (-2310 3860);
PAINT ORANGE (-2310 3860);
FORCEPROP 2 LASTPIN (-2300 3800) $PN K8
J 2
(-2310 3810);
DISPLAY 0.617021 (-2310 3810);
PAINT ORANGE (-2310 3810);
FORCEPROP 2 LASTPIN (-2300 3750) $PN N12
J 2
(-2310 3760);
DISPLAY 0.617021 (-2310 3760);
PAINT ORANGE (-2310 3760);
FORCEPROP 2 LASTPIN (-2300 3700) $PN K9
J 2
(-2310 3710);
DISPLAY 0.617021 (-2310 3710);
PAINT ORANGE (-2310 3710);
FORCEPROP 2 LASTPIN (-2300 3650) $PN M13
J 2
(-2310 3660);
DISPLAY 0.617021 (-2310 3660);
PAINT ORANGE (-2310 3660);
FORCEPROP 2 LASTPIN (-2300 3600) $PN J10
J 2
(-2310 3610);
DISPLAY 0.617021 (-2310 3610);
PAINT ORANGE (-2310 3610);
FORCEPROP 2 LASTPIN (-2300 3550) $PN H10
J 2
(-2310 3560);
DISPLAY 0.617021 (-2310 3560);
PAINT ORANGE (-2310 3560);
FORCEPROP 2 LASTPIN (-2300 3500) $PN E13
J 2
(-2310 3510);
DISPLAY 0.617021 (-2310 3510);
PAINT ORANGE (-2310 3510);
FORCEPROP 2 LASTPIN (-2300 3400) $PN G9
J 2
(-2310 3410);
DISPLAY 0.617021 (-2310 3410);
PAINT ORANGE (-2310 3410);
FORCEPROP 2 LASTPIN (-2300 3350) $PN D12
J 2
(-2310 3360);
DISPLAY 0.617021 (-2310 3360);
PAINT ORANGE (-2310 3360);
FORCEPROP 2 LASTPIN (-2300 3300) $PN G8
J 2
(-2310 3310);
DISPLAY 0.617021 (-2310 3310);
PAINT ORANGE (-2310 3310);
FORCEPROP 2 LASTPIN (-2300 4500) $PN K10
J 2
(-2310 4510);
DISPLAY 0.617021 (-2310 4510);
PAINT ORANGE (-2310 4510);
FORCEPROP 2 LASTPIN (-2300 4450) $PN K7
J 2
(-2310 4460);
DISPLAY 0.617021 (-2310 4460);
PAINT ORANGE (-2310 4460);
FORCEPROP 2 LASTPIN (-2300 4400) $PN G10
J 2
(-2310 4410);
DISPLAY 0.617021 (-2310 4410);
PAINT ORANGE (-2310 4410);
FORCEPROP 2 LASTPIN (-2300 4350) $PN G7
J 2
(-2310 4360);
DISPLAY 0.617021 (-2310 4360);
PAINT ORANGE (-2310 4360);
FORCEPROP 2 LASTPIN (-1400 4350) $PN R2
J 0
(-1390 4360);
DISPLAY 0.617021 (-1390 4360);
PAINT ORANGE (-1390 4360);
FORCEPROP 2 LASTPIN (-1400 4300) $PN P14
J 0
(-1390 4310);
DISPLAY 0.617021 (-1390 4310);
PAINT ORANGE (-1390 4310);
FORCEPROP 2 LASTPIN (-1400 4250) $PN P3
J 0
(-1390 4260);
DISPLAY 0.617021 (-1390 4260);
PAINT ORANGE (-1390 4260);
FORCEPROP 2 LASTPIN (-1400 4200) $PN N13
J 0
(-1390 4210);
DISPLAY 0.617021 (-1390 4210);
PAINT ORANGE (-1390 4210);
FORCEPROP 2 LASTPIN (-1400 4150) $PN N4
J 0
(-1390 4160);
DISPLAY 0.617021 (-1390 4160);
PAINT ORANGE (-1390 4160);
FORCEPROP 2 LASTPIN (-1400 4100) $PN M12
J 0
(-1390 4110);
DISPLAY 0.617021 (-1390 4110);
PAINT ORANGE (-1390 4110);
FORCEPROP 2 LASTPIN (-1400 4050) $PN M5
J 0
(-1390 4060);
DISPLAY 0.617021 (-1390 4060);
PAINT ORANGE (-1390 4060);
FORCEPROP 2 LASTPIN (-1400 4000) $PN L11
J 0
(-1390 4010);
DISPLAY 0.617021 (-1390 4010);
PAINT ORANGE (-1390 4010);
FORCEPROP 2 LASTPIN (-1400 3900) $PN J9
J 0
(-1390 3910);
DISPLAY 0.617021 (-1390 3910);
PAINT ORANGE (-1390 3910);
FORCEPROP 2 LASTPIN (-1400 3850) $PN J8
J 0
(-1390 3860);
DISPLAY 0.617021 (-1390 3860);
PAINT ORANGE (-1390 3860);
FORCEPROP 2 LASTPIN (-1400 3800) $PN H9
J 0
(-1390 3810);
DISPLAY 0.617021 (-1390 3810);
PAINT ORANGE (-1390 3810);
FORCEPROP 2 LASTPIN (-1400 3750) $PN H8
J 0
(-1390 3760);
DISPLAY 0.617021 (-1390 3760);
PAINT ORANGE (-1390 3760);
FORCEPROP 2 LASTPIN (-1400 3700) $PN F11
J 0
(-1390 3710);
DISPLAY 0.617021 (-1390 3710);
PAINT ORANGE (-1390 3710);
FORCEPROP 2 LASTPIN (-1400 3650) $PN F6
J 0
(-1390 3660);
DISPLAY 0.617021 (-1390 3660);
PAINT ORANGE (-1390 3660);
FORCEPROP 2 LASTPIN (-1400 3600) $PN E12
J 0
(-1390 3610);
DISPLAY 0.617021 (-1390 3610);
PAINT ORANGE (-1390 3610);
FORCEPROP 2 LASTPIN (-1400 3550) $PN E5
J 0
(-1390 3560);
DISPLAY 0.617021 (-1390 3560);
PAINT ORANGE (-1390 3560);
FORCEPROP 2 LASTPIN (-1400 3500) $PN D13
J 0
(-1390 3510);
DISPLAY 0.617021 (-1390 3510);
PAINT ORANGE (-1390 3510);
FORCEPROP 2 LASTPIN (-1400 3450) $PN D4
J 0
(-1390 3460);
DISPLAY 0.617021 (-1390 3460);
PAINT ORANGE (-1390 3460);
FORCEPROP 2 LASTPIN (-1400 3400) $PN C14
J 0
(-1390 3410);
DISPLAY 0.617021 (-1390 3410);
PAINT ORANGE (-1390 3410);
FORCEPROP 2 LASTPIN (-1400 3350) $PN C3
J 0
(-1390 3360);
DISPLAY 0.617021 (-1390 3360);
PAINT ORANGE (-1390 3360);
FORCEPROP 2 LASTPIN (-1400 3300) $PN B15
J 0
(-1390 3310);
DISPLAY 0.617021 (-1390 3310);
PAINT ORANGE (-1390 3310);
FORCEPROP 2 LASTPIN (-1400 3250) $PN B2
J 0
(-1390 3260);
DISPLAY 0.617021 (-1390 3260);
PAINT ORANGE (-1390 3260);
FORCEPROP 2 LASTPIN (-1400 4550) $PN A2
J 0
(-1390 4560);
DISPLAY 0.617021 (-1390 4560);
PAINT ORANGE (-1390 4560);
FORCEPROP 2 LASTPIN (-1400 4400) $PN R15
J 0
(-1390 4410);
DISPLAY 0.617021 (-1390 4410);
PAINT ORANGE (-1390 4410);
FORCEPROP 2 LASTPIN (-1400 3950) $PN L6
J 0
(-1390 3960);
DISPLAY 0.617021 (-1390 3960);
PAINT ORANGE (-1390 3960);
FORCEPROP 2 LASTPIN (-2300 4150) $PN A1
J 2
(-2310 4160);
DISPLAY 0.617021 (-2310 4160);
PAINT ORANGE (-2310 4160);
FORCEPROP 2 LASTPIN (-2300 4200) $PN A16
J 2
(-2310 4210);
DISPLAY 0.617021 (-2310 4210);
PAINT ORANGE (-2310 4210);
FORCEPROP 2 LASTPIN (-2300 4250) $PN T1
J 2
(-2310 4260);
DISPLAY 0.617021 (-2310 4260);
PAINT ORANGE (-2310 4260);
FORCEPROP 2 LASTPIN (-2300 4300) $PN T16
J 2
(-2310 4310);
DISPLAY 0.617021 (-2310 4310);
PAINT ORANGE (-2310 4310);
FORCEPROP 1 LAST PACK_TYPE 256BGA
J 0
(-2275 4776);
PAINT SKYBLUE (-2275 4776);
DISPLAY INVISIBLE (-2275 4776);
FORCEPROP 2 LAST ROOM CPLD
J 0
(-2250 4775);
DISPLAY 1.361702 (-2250 4775);
PAINT ORANGE (-2250 4775);
DISPLAY INVISIBLE (-2250 4775);
FORCEPROP 2 LAST SEC_TYPE 256BGA
J 0
(-2250 4775);
DISPLAY 1.021277 (-2250 4775);
PAINT ORANGE (-2250 4775);
DISPLAY INVISIBLE (-2250 4775);
FORCEPROP 2 LAST SEC 3
J 0
(-2250 4775);
DISPLAY 0.680851 (-2250 4775);
PAINT MONO (-2250 4775);
DISPLAY INVISIBLE (-2250 4775);
FORCEPROP 2 LAST CDS_LIB mstr_memory
J 0
(-1850 3900);
PAINT ORANGE (-1850 3900);
DISPLAY INVISIBLE (-1850 3900);
FORCEPROP 1 LAST CDS_LMAN_SYM_OUTLINE -400,750,400,-750
J 0
(-1850 3900);
DISPLAY 0.468085 (-1850 3900);
PAINT GREEN (-1850 3900);
DISPLAY INVISIBLE (-1850 3900);
FORCEPROP 1 LAST PATH I14
J 0
(-1624 4676);
PAINT GREEN (-1624 4676);
DISPLAY INVISIBLE (-1624 4676);
FORCEPROP 2 LAST BOM_COST CPLD
J 0
(-2250 4825);
DISPLAY 1.361702 (-2250 4825);
PAINT ORANGE (-2250 4825);
DISPLAY INVISIBLE (-2250 4825);
FORCEPROP 2 LAST CDS_LOCATION U8D7
J 0
(-2274 4726);
DISPLAY 0.617021 (-2274 4726);
PAINT AQUA (-2274 4726);
DISPLAY INVISIBLE (-2274 4726);
FORCEADD CAP_A..1
(-4550 1975);
FORCEPROP 1 LAST LOCATION C2R5
J 0
(-4500 2075);
DISPLAY 0.617021 (-4500 2075);
PAINT AQUA (-4500 2075);
FORCEPROP 1 LAST PART_NUMBER A36096-030
J 0
(-4500 1825);
DISPLAY 0.617021 (-4500 1825);
PAINT BLUE (-4500 1825);
FORCEPROP 1 LAST VALUE 0.1UF
J 0
(-4500 2025);
DISPLAY 0.617021 (-4500 2025);
PAINT SKYBLUE (-4500 2025);
FORCEPROP 1 LAST TOLERANCE 10%
J 0
(-4500 1925);
DISPLAY 0.617021 (-4500 1925);
PAINT SKYBLUE (-4500 1925);
FORCEPROP 1 LAST PACK_TYPE 0402V
J 0
(-4500 1775);
DISPLAY 0.617021 (-4500 1775);
PAINT SKYBLUE (-4500 1775);
FORCEPROP 1 LAST VOLTAGE 16V
J 0
(-4500 1975);
DISPLAY 0.617021 (-4500 1975);
PAINT SKYBLUE (-4500 1975);
FORCEPROP 1 LAST MATERIAL X7R
J 0
(-4500 1875);
DISPLAY 0.617021 (-4500 1875);
PAINT SKYBLUE (-4500 1875);
FORCEPROP 1 LASTPIN (-4550 2075) $PN 1
J 0
(-4540 2055);
DISPLAY 0.617021 (-4540 2055);
PAINT ORANGE (-4540 2055);
FORCEPROP 1 LASTPIN (-4550 1875) $PN 2
J 0
(-4540 1855);
DISPLAY 0.617021 (-4540 1855);
PAINT ORANGE (-4540 1855);
FORCEPROP 2 LAST ROOM CPLD
J 0
(-4500 2125);
DISPLAY 1.361702 (-4500 2125);
PAINT ORANGE (-4500 2125);
DISPLAY INVISIBLE (-4500 2125);
FORCEPROP 2 LAST SIGNAL_MODEL DEFAULT_CAPACITOR_100000pF_2_1
J 0
(-4500 2175);
PAINT MONO (-4500 2175);
DISPLAY INVISIBLE (-4500 2175);
FORCEPROP 2 LAST BOM_COST CPLD
J 0
(-4500 2175);
DISPLAY 1.361702 (-4500 2175);
PAINT ORANGE (-4500 2175);
DISPLAY INVISIBLE (-4500 2175);
FORCEPROP 2 LAST CDS_SEC 1
J 0
(-4500 2175);
PAINT MONO (-4500 2175);
DISPLAY INVISIBLE (-4500 2175);
FORCEPROP 2 LAST $SEC 1
J 0
(-4500 2175);
PAINT MONO (-4500 2175);
DISPLAY INVISIBLE (-4500 2175);
FORCEPROP 1 LAST PATH I15
J 0
(-4500 2125);
DISPLAY 0.978723 (-4500 2125);
PAINT WHITE (-4500 2125);
DISPLAY INVISIBLE (-4500 2125);
FORCEPROP 2 LAST CDS_LOCATION C2R5
J 0
(-4500 2075);
DISPLAY 0.617021 (-4500 2075);
PAINT AQUA (-4500 2075);
DISPLAY INVISIBLE (-4500 2075);
FORCEPROP 2 LAST CDS_LIB dev_discrete
J 0
(-4550 1975);
PAINT ORANGE (-4550 1975);
DISPLAY INVISIBLE (-4550 1975);
FORCEADD CAP_A..1
(-5025 1975);
FORCEPROP 1 LAST LOCATION C2P4
J 0
(-4975 2075);
DISPLAY 0.617021 (-4975 2075);
PAINT AQUA (-4975 2075);
FORCEPROP 1 LAST PART_NUMBER A36096-030
J 0
(-4975 1825);
DISPLAY 0.617021 (-4975 1825);
PAINT BLUE (-4975 1825);
FORCEPROP 1 LAST VALUE 0.1UF
J 0
(-4975 2025);
DISPLAY 0.617021 (-4975 2025);
PAINT SKYBLUE (-4975 2025);
FORCEPROP 1 LAST TOLERANCE 10%
J 0
(-4975 1925);
DISPLAY 0.617021 (-4975 1925);
PAINT SKYBLUE (-4975 1925);
FORCEPROP 1 LAST PACK_TYPE 0402V
J 0
(-4975 1775);
DISPLAY 0.617021 (-4975 1775);
PAINT SKYBLUE (-4975 1775);
FORCEPROP 1 LAST VOLTAGE 16V
J 0
(-4975 1975);
DISPLAY 0.617021 (-4975 1975);
PAINT SKYBLUE (-4975 1975);
FORCEPROP 1 LAST MATERIAL X7R
J 0
(-4975 1875);
DISPLAY 0.617021 (-4975 1875);
PAINT SKYBLUE (-4975 1875);
FORCEPROP 1 LASTPIN (-5025 2075) $PN 1
J 0
(-5015 2055);
DISPLAY 0.617021 (-5015 2055);
PAINT ORANGE (-5015 2055);
FORCEPROP 1 LASTPIN (-5025 1875) $PN 2
J 0
(-5015 1855);
DISPLAY 0.617021 (-5015 1855);
PAINT ORANGE (-5015 1855);
FORCEPROP 2 LAST ROOM CPLD
J 0
(-4975 2125);
DISPLAY 1.361702 (-4975 2125);
PAINT ORANGE (-4975 2125);
DISPLAY INVISIBLE (-4975 2125);
FORCEPROP 1 LAST PATH I16
J 0
(-4975 2125);
DISPLAY 0.978723 (-4975 2125);
PAINT WHITE (-4975 2125);
DISPLAY INVISIBLE (-4975 2125);
FORCEPROP 2 LAST CDS_LOCATION C2P4
J 0
(-4975 2075);
DISPLAY 0.617021 (-4975 2075);
PAINT AQUA (-4975 2075);
DISPLAY INVISIBLE (-4975 2075);
FORCEPROP 2 LAST SIGNAL_MODEL DEFAULT_CAPACITOR_100000pF_2_1
J 0
(-4975 2175);
PAINT MONO (-4975 2175);
DISPLAY INVISIBLE (-4975 2175);
FORCEPROP 2 LAST BOM_COST CPLD
J 0
(-4975 2175);
DISPLAY 1.361702 (-4975 2175);
PAINT ORANGE (-4975 2175);
DISPLAY INVISIBLE (-4975 2175);
FORCEPROP 2 LAST CDS_SEC 1
J 0
(-4975 2175);
PAINT MONO (-4975 2175);
DISPLAY INVISIBLE (-4975 2175);
FORCEPROP 2 LAST $SEC 1
J 0
(-4975 2175);
PAINT MONO (-4975 2175);
DISPLAY INVISIBLE (-4975 2175);
FORCEPROP 2 LAST CDS_LIB dev_discrete
J 0
(-5025 1975);
PAINT ORANGE (-5025 1975);
DISPLAY INVISIBLE (-5025 1975);
FORCEADD CAP_A..1
(-4725 1300);
FORCEPROP 1 LAST LOCATION C3P52
J 0
(-4675 1400);
DISPLAY 0.617021 (-4675 1400);
PAINT AQUA (-4675 1400);
FORCEPROP 1 LAST PART_NUMBER A36096-030
J 0
(-4675 1150);
DISPLAY 0.617021 (-4675 1150);
PAINT BLUE (-4675 1150);
FORCEPROP 1 LAST VALUE 0.1UF
J 0
(-4675 1350);
DISPLAY 0.617021 (-4675 1350);
PAINT SKYBLUE (-4675 1350);
FORCEPROP 1 LAST TOLERANCE 10%
J 0
(-4675 1250);
DISPLAY 0.617021 (-4675 1250);
PAINT SKYBLUE (-4675 1250);
FORCEPROP 1 LAST PACK_TYPE 0402V
J 0
(-4675 1100);
DISPLAY 0.617021 (-4675 1100);
PAINT SKYBLUE (-4675 1100);
FORCEPROP 1 LAST VOLTAGE 16V
J 0
(-4675 1300);
DISPLAY 0.617021 (-4675 1300);
PAINT SKYBLUE (-4675 1300);
FORCEPROP 1 LAST MATERIAL X7R
J 0
(-4675 1200);
DISPLAY 0.617021 (-4675 1200);
PAINT SKYBLUE (-4675 1200);
FORCEPROP 1 LASTPIN (-4725 1400) $PN 1
J 0
(-4715 1380);
DISPLAY 0.617021 (-4715 1380);
PAINT ORANGE (-4715 1380);
FORCEPROP 1 LASTPIN (-4725 1200) $PN 2
J 0
(-4715 1180);
DISPLAY 0.617021 (-4715 1180);
PAINT ORANGE (-4715 1180);
FORCEPROP 2 LAST ROOM CPLD
J 0
(-4675 1450);
DISPLAY 1.361702 (-4675 1450);
PAINT ORANGE (-4675 1450);
DISPLAY INVISIBLE (-4675 1450);
FORCEPROP 2 LAST CDS_SEC 1
J 0
(-4675 1500);
DISPLAY 1.361702 (-4675 1500);
PAINT ORANGE (-4675 1500);
DISPLAY INVISIBLE (-4675 1500);
FORCEPROP 2 LAST $SEC 1
J 0
(-4675 1500);
DISPLAY 0.914894 (-4675 1500);
PAINT MONO (-4675 1500);
DISPLAY INVISIBLE (-4675 1500);
FORCEPROP 2 LAST BOM_COST CPLD
J 0
(-4675 1500);
DISPLAY 1.361702 (-4675 1500);
PAINT ORANGE (-4675 1500);
DISPLAY INVISIBLE (-4675 1500);
FORCEPROP 2 LAST SIGNAL_MODEL DEFAULT_CAPACITOR_100000pF_2_1
J 0
(-4675 1500);
PAINT MONO (-4675 1500);
DISPLAY INVISIBLE (-4675 1500);
FORCEPROP 1 LAST PATH I17
J 0
(-4675 1450);
DISPLAY 0.978723 (-4675 1450);
PAINT WHITE (-4675 1450);
DISPLAY INVISIBLE (-4675 1450);
FORCEPROP 2 LAST CDS_LOCATION C3P52
J 0
(-4675 1400);
DISPLAY 0.617021 (-4675 1400);
PAINT AQUA (-4675 1400);
DISPLAY INVISIBLE (-4675 1400);
FORCEPROP 2 LAST CDS_LIB dev_discrete
J 0
(-4725 1300);
PAINT ORANGE (-4725 1300);
DISPLAY INVISIBLE (-4725 1300);
FORCEADD CAP_A..1
(-5225 1300);
FORCEPROP 1 LAST LOCATION C2P6
J 0
(-5175 1400);
DISPLAY 0.617021 (-5175 1400);
PAINT AQUA (-5175 1400);
FORCEPROP 1 LAST PART_NUMBER A36096-030
J 0
(-5175 1150);
DISPLAY 0.617021 (-5175 1150);
PAINT BLUE (-5175 1150);
FORCEPROP 1 LAST VALUE 0.1UF
J 0
(-5175 1350);
DISPLAY 0.617021 (-5175 1350);
PAINT SKYBLUE (-5175 1350);
FORCEPROP 1 LAST TOLERANCE 10%
J 0
(-5175 1250);
DISPLAY 0.617021 (-5175 1250);
PAINT SKYBLUE (-5175 1250);
FORCEPROP 1 LAST PACK_TYPE 0402V
J 0
(-5175 1100);
DISPLAY 0.617021 (-5175 1100);
PAINT SKYBLUE (-5175 1100);
FORCEPROP 1 LAST VOLTAGE 16V
J 0
(-5175 1300);
DISPLAY 0.617021 (-5175 1300);
PAINT SKYBLUE (-5175 1300);
FORCEPROP 1 LAST MATERIAL X7R
J 0
(-5175 1200);
DISPLAY 0.617021 (-5175 1200);
PAINT SKYBLUE (-5175 1200);
FORCEPROP 1 LASTPIN (-5225 1400) $PN 1
J 0
(-5215 1380);
DISPLAY 0.617021 (-5215 1380);
PAINT ORANGE (-5215 1380);
FORCEPROP 1 LASTPIN (-5225 1200) $PN 2
J 0
(-5215 1180);
DISPLAY 0.617021 (-5215 1180);
PAINT ORANGE (-5215 1180);
FORCEPROP 2 LAST ROOM CPLD
J 0
(-5175 1450);
DISPLAY 1.361702 (-5175 1450);
PAINT ORANGE (-5175 1450);
DISPLAY INVISIBLE (-5175 1450);
FORCEPROP 2 LAST $SEC 1
J 0
(-5175 1500);
DISPLAY 0.914894 (-5175 1500);
PAINT MONO (-5175 1500);
DISPLAY INVISIBLE (-5175 1500);
FORCEPROP 2 LAST CDS_SEC 1
J 0
(-5175 1500);
DISPLAY 1.361702 (-5175 1500);
PAINT ORANGE (-5175 1500);
DISPLAY INVISIBLE (-5175 1500);
FORCEPROP 2 LAST BOM_COST CPLD
J 0
(-5175 1500);
DISPLAY 1.361702 (-5175 1500);
PAINT ORANGE (-5175 1500);
DISPLAY INVISIBLE (-5175 1500);
FORCEPROP 2 LAST SIGNAL_MODEL DEFAULT_CAPACITOR_100000pF_2_1
J 0
(-5175 1500);
PAINT MONO (-5175 1500);
DISPLAY INVISIBLE (-5175 1500);
FORCEPROP 1 LAST PATH I18
J 0
(-5175 1450);
DISPLAY 0.978723 (-5175 1450);
PAINT WHITE (-5175 1450);
DISPLAY INVISIBLE (-5175 1450);
FORCEPROP 2 LAST CDS_LOCATION C2P6
J 0
(-5175 1400);
DISPLAY 0.617021 (-5175 1400);
PAINT AQUA (-5175 1400);
DISPLAY INVISIBLE (-5175 1400);
FORCEPROP 2 LAST CDS_LIB dev_discrete
J 0
(-5225 1300);
PAINT ORANGE (-5225 1300);
DISPLAY INVISIBLE (-5225 1300);
FORCEADD CAP_A..1
(-5500 1975);
FORCEPROP 1 LAST LOCATION C2R3
J 0
(-5450 2075);
DISPLAY 0.617021 (-5450 2075);
PAINT AQUA (-5450 2075);
FORCEPROP 1 LAST PART_NUMBER A36096-030
J 0
(-5450 1825);
DISPLAY 0.617021 (-5450 1825);
PAINT BLUE (-5450 1825);
FORCEPROP 1 LAST VALUE 0.1UF
J 0
(-5450 2025);
DISPLAY 0.617021 (-5450 2025);
PAINT SKYBLUE (-5450 2025);
FORCEPROP 1 LAST TOLERANCE 10%
J 0
(-5450 1925);
DISPLAY 0.617021 (-5450 1925);
PAINT SKYBLUE (-5450 1925);
FORCEPROP 1 LAST PACK_TYPE 0402V
J 0
(-5450 1775);
DISPLAY 0.617021 (-5450 1775);
PAINT SKYBLUE (-5450 1775);
FORCEPROP 1 LAST VOLTAGE 16V
J 0
(-5450 1975);
DISPLAY 0.617021 (-5450 1975);
PAINT SKYBLUE (-5450 1975);
FORCEPROP 1 LAST MATERIAL X7R
J 0
(-5450 1875);
DISPLAY 0.617021 (-5450 1875);
PAINT SKYBLUE (-5450 1875);
FORCEPROP 1 LASTPIN (-5500 2075) $PN 1
J 0
(-5490 2055);
DISPLAY 0.617021 (-5490 2055);
PAINT ORANGE (-5490 2055);
FORCEPROP 1 LASTPIN (-5500 1875) $PN 2
J 0
(-5490 1855);
DISPLAY 0.617021 (-5490 1855);
PAINT ORANGE (-5490 1855);
FORCEPROP 2 LAST ROOM CPLD
J 0
(-5450 2125);
DISPLAY 1.361702 (-5450 2125);
PAINT ORANGE (-5450 2125);
DISPLAY INVISIBLE (-5450 2125);
FORCEPROP 2 LAST $SEC 1
J 0
(-5450 2175);
PAINT MONO (-5450 2175);
DISPLAY INVISIBLE (-5450 2175);
FORCEPROP 2 LAST CDS_SEC 1
J 0
(-5450 2175);
PAINT MONO (-5450 2175);
DISPLAY INVISIBLE (-5450 2175);
FORCEPROP 2 LAST BOM_COST CPLD
J 0
(-5450 2175);
DISPLAY 1.361702 (-5450 2175);
PAINT ORANGE (-5450 2175);
DISPLAY INVISIBLE (-5450 2175);
FORCEPROP 2 LAST SIGNAL_MODEL DEFAULT_CAPACITOR_100000pF_2_1
J 0
(-5450 2175);
PAINT MONO (-5450 2175);
DISPLAY INVISIBLE (-5450 2175);
FORCEPROP 2 LAST CDS_LOCATION C2R3
J 0
(-5450 2075);
DISPLAY 0.617021 (-5450 2075);
PAINT AQUA (-5450 2075);
DISPLAY INVISIBLE (-5450 2075);
FORCEPROP 1 LAST PATH I19
J 0
(-5450 2125);
DISPLAY 0.978723 (-5450 2125);
PAINT WHITE (-5450 2125);
DISPLAY INVISIBLE (-5450 2125);
FORCEPROP 2 LAST CDS_LIB dev_discrete
J 0
(-5500 1975);
PAINT ORANGE (-5500 1975);
DISPLAY INVISIBLE (-5500 1975);
FORCEADD GND..1
(-1225 1625);
FORCEPROP 3 LASTPIN (-1225 1675) SIG_NAME GND\g
J 0
(-1215 1685);
DISPLAY 0.659574 (-1215 1685);
PAINT MONO (-1215 1685);
DISPLAY INVISIBLE (-1215 1685);
FORCEPROP 1 LAST VOLTAGE 0.0V
J 0
(-1270 1582);
DISPLAY 0.340426 (-1270 1582);
PAINT SKYBLUE (-1270 1582);
DISPLAY INVISIBLE (-1270 1582);
FORCEPROP 1 LAST HDL_POWER GND
J 0
(-1225 1775);
DISPLAY 1.170213 (-1225 1775);
PAINT GREEN (-1225 1775);
DISPLAY INVISIBLE (-1225 1775);
FORCEPROP 2 LAST ROOM CPLD
J 0
(-1450 1700);
DISPLAY 1.361702 (-1450 1700);
PAINT ORANGE (-1450 1700);
DISPLAY INVISIBLE (-1450 1700);
FORCEPROP 1 LAST SIZE 1B
J 0
(-1150 1575);
DISPLAY 1.170213 (-1150 1575);
PAINT AQUA (-1150 1575);
DISPLAY INVISIBLE (-1150 1575);
FORCEPROP 1 LAST PATH I2
J 0
(-1150 1625);
DISPLAY 0.872340 (-1150 1625);
PAINT AQUA (-1150 1625);
DISPLAY INVISIBLE (-1150 1625);
FORCEPROP 2 LAST CDS_LIB mstr_symbols
J 0
(-1225 1625);
PAINT ORANGE (-1225 1625);
DISPLAY INVISIBLE (-1225 1625);
FORCEPROP 1 LAST BODY_TYPE PLUMBING
J 0
(-1270 1582);
DISPLAY 0.340426 (-1270 1582);
PAINT GREEN (-1270 1582);
DISPLAY INVISIBLE (-1270 1582);
FORCEPROP 2 LAST BOM_COST CPLD
J 0
(-1450 1750);
DISPLAY 1.361702 (-1450 1750);
PAINT ORANGE (-1450 1750);
DISPLAY INVISIBLE (-1450 1750);
FORCEADD CAP_A..1
(-5975 1975);
FORCEPROP 1 LAST LOCATION C2P7
J 0
(-5925 2075);
DISPLAY 0.617021 (-5925 2075);
PAINT AQUA (-5925 2075);
FORCEPROP 1 LAST PART_NUMBER A36096-030
J 0
(-5925 1825);
DISPLAY 0.617021 (-5925 1825);
PAINT BLUE (-5925 1825);
FORCEPROP 1 LAST VALUE 0.1UF
J 0
(-5925 2025);
DISPLAY 0.617021 (-5925 2025);
PAINT SKYBLUE (-5925 2025);
FORCEPROP 1 LAST TOLERANCE 10%
J 0
(-5925 1925);
DISPLAY 0.617021 (-5925 1925);
PAINT SKYBLUE (-5925 1925);
FORCEPROP 1 LAST PACK_TYPE 0402V
J 0
(-5925 1775);
DISPLAY 0.617021 (-5925 1775);
PAINT SKYBLUE (-5925 1775);
FORCEPROP 1 LAST VOLTAGE 16V
J 0
(-5925 1975);
DISPLAY 0.617021 (-5925 1975);
PAINT SKYBLUE (-5925 1975);
FORCEPROP 1 LAST MATERIAL X7R
J 0
(-5925 1875);
DISPLAY 0.617021 (-5925 1875);
PAINT SKYBLUE (-5925 1875);
FORCEPROP 1 LASTPIN (-5975 2075) $PN 1
J 0
(-5965 2055);
DISPLAY 0.617021 (-5965 2055);
PAINT ORANGE (-5965 2055);
FORCEPROP 1 LASTPIN (-5975 1875) $PN 2
J 0
(-5965 1855);
DISPLAY 0.617021 (-5965 1855);
PAINT ORANGE (-5965 1855);
FORCEPROP 2 LAST ROOM CPLD
J 0
(-5925 2125);
DISPLAY 1.361702 (-5925 2125);
PAINT ORANGE (-5925 2125);
DISPLAY INVISIBLE (-5925 2125);
FORCEPROP 2 LAST $SEC 1
J 0
(-5925 2175);
PAINT MONO (-5925 2175);
DISPLAY INVISIBLE (-5925 2175);
FORCEPROP 2 LAST CDS_SEC 1
J 0
(-5925 2175);
PAINT MONO (-5925 2175);
DISPLAY INVISIBLE (-5925 2175);
FORCEPROP 2 LAST SIGNAL_MODEL DEFAULT_CAPACITOR_100000pF_2_1
J 0
(-5925 2175);
PAINT MONO (-5925 2175);
DISPLAY INVISIBLE (-5925 2175);
FORCEPROP 2 LAST BOM_COST CPLD
J 0
(-5925 2175);
DISPLAY 1.361702 (-5925 2175);
PAINT ORANGE (-5925 2175);
DISPLAY INVISIBLE (-5925 2175);
FORCEPROP 2 LAST CDS_LOCATION C2P7
J 0
(-5925 2075);
DISPLAY 0.617021 (-5925 2075);
PAINT AQUA (-5925 2075);
DISPLAY INVISIBLE (-5925 2075);
FORCEPROP 1 LAST PATH I20
J 0
(-5925 2125);
DISPLAY 0.978723 (-5925 2125);
PAINT WHITE (-5925 2125);
DISPLAY INVISIBLE (-5925 2125);
FORCEPROP 2 LAST CDS_LIB dev_discrete
J 0
(-5975 1975);
PAINT ORANGE (-5975 1975);
DISPLAY INVISIBLE (-5975 1975);
FORCEADD CAP_A..1
(-5700 1300);
FORCEPROP 1 LAST LOCATION C2R4
J 0
(-5650 1400);
DISPLAY 0.617021 (-5650 1400);
PAINT AQUA (-5650 1400);
FORCEPROP 1 LAST PART_NUMBER A36096-030
J 0
(-5650 1150);
DISPLAY 0.617021 (-5650 1150);
PAINT BLUE (-5650 1150);
FORCEPROP 1 LAST VALUE 0.1UF
J 0
(-5650 1350);
DISPLAY 0.617021 (-5650 1350);
PAINT SKYBLUE (-5650 1350);
FORCEPROP 1 LAST TOLERANCE 10%
J 0
(-5650 1250);
DISPLAY 0.617021 (-5650 1250);
PAINT SKYBLUE (-5650 1250);
FORCEPROP 1 LAST PACK_TYPE 0402V
J 0
(-5650 1100);
DISPLAY 0.617021 (-5650 1100);
PAINT SKYBLUE (-5650 1100);
FORCEPROP 1 LAST VOLTAGE 16V
J 0
(-5650 1300);
DISPLAY 0.617021 (-5650 1300);
PAINT SKYBLUE (-5650 1300);
FORCEPROP 1 LAST MATERIAL X7R
J 0
(-5650 1200);
DISPLAY 0.617021 (-5650 1200);
PAINT SKYBLUE (-5650 1200);
FORCEPROP 1 LASTPIN (-5700 1400) $PN 1
J 0
(-5690 1380);
DISPLAY 0.617021 (-5690 1380);
PAINT ORANGE (-5690 1380);
FORCEPROP 1 LASTPIN (-5700 1200) $PN 2
J 0
(-5690 1180);
DISPLAY 0.617021 (-5690 1180);
PAINT ORANGE (-5690 1180);
FORCEPROP 2 LAST ROOM CPLD
J 0
(-5650 1450);
DISPLAY 1.361702 (-5650 1450);
PAINT ORANGE (-5650 1450);
DISPLAY INVISIBLE (-5650 1450);
FORCEPROP 2 LAST CDS_SEC 1
J 0
(-5650 1500);
DISPLAY 1.361702 (-5650 1500);
PAINT ORANGE (-5650 1500);
DISPLAY INVISIBLE (-5650 1500);
FORCEPROP 2 LAST $SEC 1
J 0
(-5650 1500);
DISPLAY 0.914894 (-5650 1500);
PAINT MONO (-5650 1500);
DISPLAY INVISIBLE (-5650 1500);
FORCEPROP 2 LAST BOM_COST CPLD
J 0
(-5650 1500);
DISPLAY 1.361702 (-5650 1500);
PAINT ORANGE (-5650 1500);
DISPLAY INVISIBLE (-5650 1500);
FORCEPROP 2 LAST SIGNAL_MODEL DEFAULT_CAPACITOR_100000pF_2_1
J 0
(-5650 1500);
PAINT MONO (-5650 1500);
DISPLAY INVISIBLE (-5650 1500);
FORCEPROP 1 LAST PATH I21
J 0
(-5650 1450);
DISPLAY 0.978723 (-5650 1450);
PAINT WHITE (-5650 1450);
DISPLAY INVISIBLE (-5650 1450);
FORCEPROP 2 LAST CDS_LOCATION C2R4
J 0
(-5650 1400);
DISPLAY 0.617021 (-5650 1400);
PAINT AQUA (-5650 1400);
DISPLAY INVISIBLE (-5650 1400);
FORCEPROP 2 LAST CDS_LIB dev_discrete
J 0
(-5700 1300);
PAINT ORANGE (-5700 1300);
DISPLAY INVISIBLE (-5700 1300);
FORCEADD CAP_A..1
(-6250 1300);
FORCEPROP 1 LAST LOCATION C2P3
J 0
(-6200 1400);
DISPLAY 0.617021 (-6200 1400);
PAINT AQUA (-6200 1400);
FORCEPROP 1 LAST PART_NUMBER A36096-030
J 0
(-6200 1150);
DISPLAY 0.617021 (-6200 1150);
PAINT BLUE (-6200 1150);
FORCEPROP 1 LAST VALUE 0.1UF
J 0
(-6200 1350);
DISPLAY 0.617021 (-6200 1350);
PAINT SKYBLUE (-6200 1350);
FORCEPROP 1 LAST TOLERANCE 10%
J 0
(-6200 1250);
DISPLAY 0.617021 (-6200 1250);
PAINT SKYBLUE (-6200 1250);
FORCEPROP 1 LAST PACK_TYPE 0402V
J 0
(-6200 1100);
DISPLAY 0.617021 (-6200 1100);
PAINT SKYBLUE (-6200 1100);
FORCEPROP 1 LAST VOLTAGE 16V
J 0
(-6200 1300);
DISPLAY 0.617021 (-6200 1300);
PAINT SKYBLUE (-6200 1300);
FORCEPROP 1 LAST MATERIAL X7R
J 0
(-6200 1200);
DISPLAY 0.617021 (-6200 1200);
PAINT SKYBLUE (-6200 1200);
FORCEPROP 1 LASTPIN (-6250 1400) $PN 1
J 0
(-6240 1380);
DISPLAY 0.617021 (-6240 1380);
PAINT ORANGE (-6240 1380);
FORCEPROP 1 LASTPIN (-6250 1200) $PN 2
J 0
(-6240 1180);
DISPLAY 0.617021 (-6240 1180);
PAINT ORANGE (-6240 1180);
FORCEPROP 2 LAST ROOM CPLD
J 0
(-6200 1450);
DISPLAY 1.361702 (-6200 1450);
PAINT ORANGE (-6200 1450);
DISPLAY INVISIBLE (-6200 1450);
FORCEPROP 2 LAST $SEC 1
J 0
(-6200 1500);
DISPLAY 0.914894 (-6200 1500);
PAINT MONO (-6200 1500);
DISPLAY INVISIBLE (-6200 1500);
FORCEPROP 2 LAST CDS_SEC 1
J 0
(-6200 1500);
DISPLAY 1.361702 (-6200 1500);
PAINT ORANGE (-6200 1500);
DISPLAY INVISIBLE (-6200 1500);
FORCEPROP 2 LAST BOM_COST CPLD
J 0
(-6200 1500);
DISPLAY 1.361702 (-6200 1500);
PAINT ORANGE (-6200 1500);
DISPLAY INVISIBLE (-6200 1500);
FORCEPROP 2 LAST SIGNAL_MODEL DEFAULT_CAPACITOR_100000pF_2_1
J 0
(-6200 1500);
PAINT MONO (-6200 1500);
DISPLAY INVISIBLE (-6200 1500);
FORCEPROP 1 LAST PATH I22
J 0
(-6200 1450);
DISPLAY 0.978723 (-6200 1450);
PAINT WHITE (-6200 1450);
DISPLAY INVISIBLE (-6200 1450);
FORCEPROP 2 LAST CDS_LOCATION C2P3
J 0
(-6200 1400);
DISPLAY 0.617021 (-6200 1400);
PAINT AQUA (-6200 1400);
DISPLAY INVISIBLE (-6200 1400);
FORCEPROP 2 LAST CDS_LIB dev_discrete
J 0
(-6250 1300);
PAINT ORANGE (-6250 1300);
DISPLAY INVISIBLE (-6250 1300);
FORCEADD CAP_A..1
(-6450 1975);
FORCEPROP 1 LAST LOCATION C3P44
J 0
(-6400 2075);
DISPLAY 0.617021 (-6400 2075);
PAINT AQUA (-6400 2075);
FORCEPROP 1 LAST PART_NUMBER A36096-030
J 0
(-6400 1825);
DISPLAY 0.617021 (-6400 1825);
PAINT BLUE (-6400 1825);
FORCEPROP 1 LAST VALUE 0.1UF
J 0
(-6400 2025);
DISPLAY 0.617021 (-6400 2025);
PAINT SKYBLUE (-6400 2025);
FORCEPROP 1 LAST TOLERANCE 10%
J 0
(-6400 1925);
DISPLAY 0.617021 (-6400 1925);
PAINT SKYBLUE (-6400 1925);
FORCEPROP 1 LAST PACK_TYPE 0402V
J 0
(-6400 1775);
DISPLAY 0.617021 (-6400 1775);
PAINT SKYBLUE (-6400 1775);
FORCEPROP 1 LAST VOLTAGE 16V
J 0
(-6400 1975);
DISPLAY 0.617021 (-6400 1975);
PAINT SKYBLUE (-6400 1975);
FORCEPROP 1 LAST MATERIAL X7R
J 0
(-6400 1875);
DISPLAY 0.617021 (-6400 1875);
PAINT SKYBLUE (-6400 1875);
FORCEPROP 1 LASTPIN (-6450 1875) $PN 2
J 0
(-6440 1855);
DISPLAY 0.617021 (-6440 1855);
PAINT ORANGE (-6440 1855);
FORCEPROP 1 LASTPIN (-6450 2075) $PN 1
J 0
(-6440 2055);
DISPLAY 0.617021 (-6440 2055);
PAINT ORANGE (-6440 2055);
FORCEPROP 2 LAST ROOM CPLD
J 0
(-6400 2125);
DISPLAY 1.361702 (-6400 2125);
PAINT ORANGE (-6400 2125);
DISPLAY INVISIBLE (-6400 2125);
FORCEPROP 1 LAST PATH I23
J 0
(-6400 2125);
DISPLAY 0.978723 (-6400 2125);
PAINT WHITE (-6400 2125);
DISPLAY INVISIBLE (-6400 2125);
FORCEPROP 2 LAST CDS_LOCATION C3P44
J 0
(-6400 2075);
DISPLAY 0.617021 (-6400 2075);
PAINT AQUA (-6400 2075);
DISPLAY INVISIBLE (-6400 2075);
FORCEPROP 2 LAST BOM_COST CPLD
J 0
(-6400 2175);
DISPLAY 1.361702 (-6400 2175);
PAINT ORANGE (-6400 2175);
DISPLAY INVISIBLE (-6400 2175);
FORCEPROP 2 LAST SIGNAL_MODEL DEFAULT_CAPACITOR_100000pF_2_1
J 0
(-6400 2175);
PAINT MONO (-6400 2175);
DISPLAY INVISIBLE (-6400 2175);
FORCEPROP 2 LAST CDS_SEC 1
J 0
(-6400 2175);
PAINT MONO (-6400 2175);
DISPLAY INVISIBLE (-6400 2175);
FORCEPROP 2 LAST $SEC 1
J 0
(-6400 2175);
PAINT MONO (-6400 2175);
DISPLAY INVISIBLE (-6400 2175);
FORCEPROP 2 LAST CDS_LIB dev_discrete
J 0
(-6450 1975);
PAINT ORANGE (-6450 1975);
DISPLAY INVISIBLE (-6450 1975);
FORCEADD CAP_A..1
(-6925 1975);
FORCEPROP 1 LAST LOCATION C3P48
J 0
(-6875 2075);
DISPLAY 0.617021 (-6875 2075);
PAINT AQUA (-6875 2075);
FORCEPROP 1 LAST PART_NUMBER A36096-030
J 0
(-6875 1825);
DISPLAY 0.617021 (-6875 1825);
PAINT BLUE (-6875 1825);
FORCEPROP 1 LAST VALUE 0.1UF
J 0
(-6875 2025);
DISPLAY 0.617021 (-6875 2025);
PAINT SKYBLUE (-6875 2025);
FORCEPROP 1 LAST TOLERANCE 10%
J 0
(-6875 1925);
DISPLAY 0.617021 (-6875 1925);
PAINT SKYBLUE (-6875 1925);
FORCEPROP 1 LAST PACK_TYPE 0402V
J 0
(-6875 1775);
DISPLAY 0.617021 (-6875 1775);
PAINT SKYBLUE (-6875 1775);
FORCEPROP 1 LAST VOLTAGE 16V
J 0
(-6875 1975);
DISPLAY 0.617021 (-6875 1975);
PAINT SKYBLUE (-6875 1975);
FORCEPROP 1 LAST MATERIAL X7R
J 0
(-6875 1875);
DISPLAY 0.617021 (-6875 1875);
PAINT SKYBLUE (-6875 1875);
FORCEPROP 1 LASTPIN (-6925 2075) $PN 1
J 0
(-6915 2055);
DISPLAY 0.617021 (-6915 2055);
PAINT ORANGE (-6915 2055);
FORCEPROP 1 LASTPIN (-6925 1875) $PN 2
J 0
(-6915 1855);
DISPLAY 0.617021 (-6915 1855);
PAINT ORANGE (-6915 1855);
FORCEPROP 2 LAST ROOM CPLD
J 0
(-6875 2125);
DISPLAY 1.361702 (-6875 2125);
PAINT ORANGE (-6875 2125);
DISPLAY INVISIBLE (-6875 2125);
FORCEPROP 2 LAST SEC 1
J 0
(-6875 2175);
DISPLAY 0.914894 (-6875 2175);
PAINT MONO (-6875 2175);
DISPLAY INVISIBLE (-6875 2175);
FORCEPROP 2 LAST SEC_TYPE 0402V
J 0
(-6875 2175);
DISPLAY 1.361702 (-6875 2175);
PAINT ORANGE (-6875 2175);
DISPLAY INVISIBLE (-6875 2175);
FORCEPROP 2 LAST CDS_SEC 1
J 0
(-6875 2125);
PAINT ORANGE (-6875 2125);
DISPLAY INVISIBLE (-6875 2125);
FORCEPROP 2 LAST BOM_COST CPLD
J 0
(-6875 2175);
DISPLAY 1.361702 (-6875 2175);
PAINT ORANGE (-6875 2175);
DISPLAY INVISIBLE (-6875 2175);
FORCEPROP 2 LAST SIGNAL_MODEL DEFAULT_CAPACITOR_100000pF_2_1
J 0
(-6875 2175);
PAINT MONO (-6875 2175);
DISPLAY INVISIBLE (-6875 2175);
FORCEPROP 2 LAST CDS_LOCATION C3P48
J 0
(-6875 2075);
DISPLAY 0.617021 (-6875 2075);
PAINT AQUA (-6875 2075);
DISPLAY INVISIBLE (-6875 2075);
FORCEPROP 1 LAST PATH I25
J 0
(-6875 2125);
DISPLAY 0.978723 (-6875 2125);
PAINT WHITE (-6875 2125);
DISPLAY INVISIBLE (-6875 2125);
FORCEPROP 2 LAST CDS_LIB dev_discrete
J 0
(-6925 1975);
PAINT ORANGE (-6925 1975);
DISPLAY INVISIBLE (-6925 1975);
FORCEADD GND..1
(-6475 1000);
FORCEPROP 3 LASTPIN (-6475 1050) SIG_NAME GND\g
J 0
(-6465 1060);
DISPLAY 0.659574 (-6465 1060);
PAINT MONO (-6465 1060);
DISPLAY INVISIBLE (-6465 1060);
FORCEPROP 1 LAST VOLTAGE 0.0V
J 0
(-6520 957);
DISPLAY 0.340426 (-6520 957);
PAINT SKYBLUE (-6520 957);
DISPLAY INVISIBLE (-6520 957);
FORCEPROP 1 LAST HDL_POWER GND
J 0
(-6475 1150);
DISPLAY 1.170213 (-6475 1150);
PAINT GREEN (-6475 1150);
DISPLAY INVISIBLE (-6475 1150);
FORCEPROP 2 LAST ROOM CPLD
J 0
(-6700 1075);
DISPLAY 1.361702 (-6700 1075);
PAINT ORANGE (-6700 1075);
DISPLAY INVISIBLE (-6700 1075);
FORCEPROP 2 LAST BOM_COST CPLD
J 0
(-6700 1125);
DISPLAY 1.361702 (-6700 1125);
PAINT ORANGE (-6700 1125);
DISPLAY INVISIBLE (-6700 1125);
FORCEPROP 1 LAST PATH I26
J 0
(-6400 1000);
DISPLAY 0.872340 (-6400 1000);
PAINT AQUA (-6400 1000);
DISPLAY INVISIBLE (-6400 1000);
FORCEPROP 2 LAST CDS_LIB mstr_symbols
J 0
(-6475 1000);
PAINT ORANGE (-6475 1000);
DISPLAY INVISIBLE (-6475 1000);
FORCEPROP 1 LAST BODY_TYPE PLUMBING
J 0
(-6520 957);
DISPLAY 0.340426 (-6520 957);
PAINT GREEN (-6520 957);
DISPLAY INVISIBLE (-6520 957);
FORCEPROP 1 LAST SIZE 1B
J 0
(-6400 950);
DISPLAY 1.170213 (-6400 950);
PAINT AQUA (-6400 950);
DISPLAY INVISIBLE (-6400 950);
FORCEADD CAP_A..1
(-6850 1300);
FORCEPROP 1 LAST LOCATION C2R2
J 0
(-6800 1400);
DISPLAY 0.617021 (-6800 1400);
PAINT AQUA (-6800 1400);
FORCEPROP 1 LAST PART_NUMBER A36096-030
J 0
(-6800 1150);
DISPLAY 0.617021 (-6800 1150);
PAINT BLUE (-6800 1150);
FORCEPROP 1 LAST VALUE 0.1UF
J 0
(-6800 1350);
DISPLAY 0.617021 (-6800 1350);
PAINT SKYBLUE (-6800 1350);
FORCEPROP 1 LAST TOLERANCE 10%
J 0
(-6800 1250);
DISPLAY 0.617021 (-6800 1250);
PAINT SKYBLUE (-6800 1250);
FORCEPROP 1 LAST PACK_TYPE 0402V
J 0
(-6800 1100);
DISPLAY 0.617021 (-6800 1100);
PAINT SKYBLUE (-6800 1100);
FORCEPROP 1 LAST VOLTAGE 16V
J 0
(-6800 1300);
DISPLAY 0.617021 (-6800 1300);
PAINT SKYBLUE (-6800 1300);
FORCEPROP 1 LAST MATERIAL X7R
J 0
(-6800 1200);
DISPLAY 0.617021 (-6800 1200);
PAINT SKYBLUE (-6800 1200);
FORCEPROP 1 LASTPIN (-6850 1400) $PN 1
J 0
(-6840 1380);
DISPLAY 0.617021 (-6840 1380);
PAINT ORANGE (-6840 1380);
FORCEPROP 1 LASTPIN (-6850 1200) $PN 2
J 0
(-6840 1180);
DISPLAY 0.617021 (-6840 1180);
PAINT ORANGE (-6840 1180);
FORCEPROP 2 LAST ROOM CPLD
J 0
(-6800 1450);
DISPLAY 1.361702 (-6800 1450);
PAINT ORANGE (-6800 1450);
DISPLAY INVISIBLE (-6800 1450);
FORCEPROP 2 LAST $SEC 1
J 0
(-6800 1500);
DISPLAY 0.914894 (-6800 1500);
PAINT MONO (-6800 1500);
DISPLAY INVISIBLE (-6800 1500);
FORCEPROP 2 LAST CDS_SEC 1
J 0
(-6800 1500);
DISPLAY 1.361702 (-6800 1500);
PAINT ORANGE (-6800 1500);
DISPLAY INVISIBLE (-6800 1500);
FORCEPROP 2 LAST BOM_COST CPLD
J 0
(-6800 1500);
DISPLAY 1.361702 (-6800 1500);
PAINT ORANGE (-6800 1500);
DISPLAY INVISIBLE (-6800 1500);
FORCEPROP 2 LAST SIGNAL_MODEL DEFAULT_CAPACITOR_100000pF_2_1
J 0
(-6800 1500);
PAINT MONO (-6800 1500);
DISPLAY INVISIBLE (-6800 1500);
FORCEPROP 1 LAST PATH I28
J 0
(-6800 1450);
DISPLAY 0.978723 (-6800 1450);
PAINT WHITE (-6800 1450);
DISPLAY INVISIBLE (-6800 1450);
FORCEPROP 2 LAST CDS_LOCATION C2R2
J 0
(-6800 1400);
DISPLAY 0.617021 (-6800 1400);
PAINT AQUA (-6800 1400);
DISPLAY INVISIBLE (-6800 1400);
FORCEPROP 2 LAST CDS_LIB dev_discrete
J 0
(-6850 1300);
PAINT ORANGE (-6850 1300);
DISPLAY INVISIBLE (-6850 1300);
FORCEADD P3V3_STBY..1
(-2500 4700);
FORCEPROP 3 LASTPIN (-2500 4650) SIG_NAME P3V3_STBY\g
J 0
(-2490 4660);
DISPLAY 0.659574 (-2490 4660);
PAINT MONO (-2490 4660);
DISPLAY INVISIBLE (-2490 4660);
FORCEPROP 1 LAST VOLTAGE 3.3V
J 0
(-2545 4657);
DISPLAY 0.340426 (-2545 4657);
PAINT SKYBLUE (-2545 4657);
DISPLAY INVISIBLE (-2545 4657);
FORCEPROP 1 LAST HDL_POWER P3V3_STBY
J 0
(-2800 4575);
DISPLAY 0.872340 (-2800 4575);
PAINT ORANGE (-2800 4575);
DISPLAY INVISIBLE (-2800 4575);
FORCEPROP 1 LAST SIZE 1B
J 0
(-2455 4722);
DISPLAY 0.340426 (-2455 4722);
PAINT GREEN (-2455 4722);
DISPLAY INVISIBLE (-2455 4722);
FORCEPROP 2 LAST CDS_LIB mstr_symbols
J 0
(-2500 4700);
PAINT ORANGE (-2500 4700);
DISPLAY INVISIBLE (-2500 4700);
FORCEPROP 1 LAST BODY_TYPE PLUMBING
J 0
(-2545 4657);
DISPLAY 0.340426 (-2545 4657);
PAINT GREEN (-2545 4657);
DISPLAY INVISIBLE (-2545 4657);
FORCEPROP 1 LAST PATH I29
J 0
(-2455 4702);
DISPLAY 0.340426 (-2455 4702);
PAINT GREEN (-2455 4702);
DISPLAY INVISIBLE (-2455 4702);
FORCEADD CAP_A..1
(-1700 1975);
FORCEPROP 1 LAST LOCATION C2P5
J 0
(-1650 2075);
DISPLAY 0.617021 (-1650 2075);
PAINT AQUA (-1650 2075);
FORCEPROP 1 LAST PART_NUMBER A36096-030
J 0
(-1650 1825);
DISPLAY 0.617021 (-1650 1825);
PAINT BLUE (-1650 1825);
FORCEPROP 1 LAST VALUE 0.1UF
J 0
(-1650 2025);
DISPLAY 0.617021 (-1650 2025);
PAINT SKYBLUE (-1650 2025);
FORCEPROP 1 LAST TOLERANCE 10%
J 0
(-1650 1925);
DISPLAY 0.617021 (-1650 1925);
PAINT SKYBLUE (-1650 1925);
FORCEPROP 1 LAST PACK_TYPE 0402V
J 0
(-1650 1775);
DISPLAY 0.617021 (-1650 1775);
PAINT SKYBLUE (-1650 1775);
FORCEPROP 1 LAST VOLTAGE 16V
J 0
(-1650 1975);
DISPLAY 0.617021 (-1650 1975);
PAINT SKYBLUE (-1650 1975);
FORCEPROP 1 LAST MATERIAL X7R
J 0
(-1650 1875);
DISPLAY 0.617021 (-1650 1875);
PAINT SKYBLUE (-1650 1875);
FORCEPROP 1 LASTPIN (-1700 2075) $PN 1
J 0
(-1690 2055);
DISPLAY 0.617021 (-1690 2055);
PAINT ORANGE (-1690 2055);
FORCEPROP 1 LASTPIN (-1700 1875) $PN 2
J 0
(-1690 1855);
DISPLAY 0.617021 (-1690 1855);
PAINT ORANGE (-1690 1855);
FORCEPROP 2 LAST ROOM CPLD
J 0
(-1650 2125);
DISPLAY 1.361702 (-1650 2125);
PAINT ORANGE (-1650 2125);
DISPLAY INVISIBLE (-1650 2125);
FORCEPROP 1 LAST PATH I3
J 0
(-1650 2125);
DISPLAY 0.978723 (-1650 2125);
PAINT WHITE (-1650 2125);
DISPLAY INVISIBLE (-1650 2125);
FORCEPROP 2 LAST CDS_LOCATION C2P5
J 0
(-1650 2075);
DISPLAY 0.617021 (-1650 2075);
PAINT AQUA (-1650 2075);
DISPLAY INVISIBLE (-1650 2075);
FORCEPROP 2 LAST SIGNAL_MODEL DEFAULT_CAPACITOR_100000pF_2_1
J 0
(-1650 2175);
PAINT MONO (-1650 2175);
DISPLAY INVISIBLE (-1650 2175);
FORCEPROP 2 LAST BOM_COST CPLD
J 0
(-1650 2175);
DISPLAY 1.361702 (-1650 2175);
PAINT ORANGE (-1650 2175);
DISPLAY INVISIBLE (-1650 2175);
FORCEPROP 2 LAST CDS_SEC 1
J 0
(-1650 2175);
PAINT MONO (-1650 2175);
DISPLAY INVISIBLE (-1650 2175);
FORCEPROP 2 LAST $SEC 1
J 0
(-1650 2175);
PAINT MONO (-1650 2175);
DISPLAY INVISIBLE (-1650 2175);
FORCEPROP 2 LAST CDS_LIB dev_discrete
J 0
(-1700 1975);
PAINT ORANGE (-1700 1975);
DISPLAY INVISIBLE (-1700 1975);
FORCEADD P3V3_STBY..1
(-6925 2275);
FORCEPROP 3 LASTPIN (-6925 2225) SIG_NAME P3V3_STBY\g
J 0
(-6915 2235);
DISPLAY 0.659574 (-6915 2235);
PAINT MONO (-6915 2235);
DISPLAY INVISIBLE (-6915 2235);
FORCEPROP 1 LAST VOLTAGE 3.3V
J 0
(-6970 2232);
DISPLAY 0.340426 (-6970 2232);
PAINT SKYBLUE (-6970 2232);
DISPLAY INVISIBLE (-6970 2232);
FORCEPROP 1 LAST HDL_POWER P3V3_STBY
J 0
(-7225 2150);
DISPLAY 0.872340 (-7225 2150);
PAINT ORANGE (-7225 2150);
DISPLAY INVISIBLE (-7225 2150);
FORCEPROP 1 LAST PATH I30
J 0
(-6880 2277);
DISPLAY 0.340426 (-6880 2277);
PAINT GREEN (-6880 2277);
DISPLAY INVISIBLE (-6880 2277);
FORCEPROP 1 LAST SIZE 1B
J 0
(-6880 2297);
DISPLAY 0.340426 (-6880 2297);
PAINT GREEN (-6880 2297);
DISPLAY INVISIBLE (-6880 2297);
FORCEPROP 2 LAST CDS_LIB mstr_symbols
J 0
(-6925 2275);
PAINT ORANGE (-6925 2275);
DISPLAY INVISIBLE (-6925 2275);
FORCEPROP 1 LAST BODY_TYPE PLUMBING
J 0
(-6970 2232);
DISPLAY 0.340426 (-6970 2232);
PAINT GREEN (-6970 2232);
DISPLAY INVISIBLE (-6970 2232);
FORCEADD P3V3_STBY..1
(-6850 1525);
FORCEPROP 3 LASTPIN (-6850 1475) SIG_NAME P3V3_STBY\g
J 0
(-6840 1485);
DISPLAY 0.659574 (-6840 1485);
PAINT MONO (-6840 1485);
DISPLAY INVISIBLE (-6840 1485);
FORCEPROP 1 LAST VOLTAGE 3.3V
J 0
(-6895 1482);
DISPLAY 0.340426 (-6895 1482);
PAINT SKYBLUE (-6895 1482);
DISPLAY INVISIBLE (-6895 1482);
FORCEPROP 1 LAST HDL_POWER P3V3_STBY
J 0
(-7150 1400);
DISPLAY 0.872340 (-7150 1400);
PAINT ORANGE (-7150 1400);
DISPLAY INVISIBLE (-7150 1400);
FORCEPROP 1 LAST SIZE 1B
J 0
(-6805 1547);
DISPLAY 0.340426 (-6805 1547);
PAINT GREEN (-6805 1547);
DISPLAY INVISIBLE (-6805 1547);
FORCEPROP 1 LAST PATH I31
J 0
(-6805 1527);
DISPLAY 0.340426 (-6805 1527);
PAINT GREEN (-6805 1527);
DISPLAY INVISIBLE (-6805 1527);
FORCEPROP 2 LAST CDS_LIB mstr_symbols
J 0
(-6850 1525);
PAINT ORANGE (-6850 1525);
DISPLAY INVISIBLE (-6850 1525);
FORCEPROP 1 LAST BODY_TYPE PLUMBING
J 0
(-6895 1482);
DISPLAY 0.340426 (-6895 1482);
PAINT GREEN (-6895 1482);
DISPLAY INVISIBLE (-6895 1482);
FORCEADD P3V3_STBY..1
(-6150 4600);
FORCEPROP 3 LASTPIN (-6150 4550) SIG_NAME P3V3_STBY\g
J 0
(-6140 4560);
DISPLAY 0.659574 (-6140 4560);
PAINT MONO (-6140 4560);
DISPLAY INVISIBLE (-6140 4560);
FORCEPROP 1 LAST VOLTAGE 3.3V
J 0
(-6195 4557);
DISPLAY 0.340426 (-6195 4557);
PAINT SKYBLUE (-6195 4557);
DISPLAY INVISIBLE (-6195 4557);
FORCEPROP 1 LAST HDL_POWER P3V3_STBY
J 0
(-6450 4475);
DISPLAY 0.872340 (-6450 4475);
PAINT ORANGE (-6450 4475);
DISPLAY INVISIBLE (-6450 4475);
FORCEPROP 1 LAST SIZE 1B
J 0
(-6105 4622);
DISPLAY 0.340426 (-6105 4622);
PAINT GREEN (-6105 4622);
DISPLAY INVISIBLE (-6105 4622);
FORCEPROP 1 LAST PATH I32
J 0
(-6105 4602);
DISPLAY 0.340426 (-6105 4602);
PAINT GREEN (-6105 4602);
DISPLAY INVISIBLE (-6105 4602);
FORCEPROP 2 LAST CDS_LIB mstr_symbols
J 0
(-6150 4600);
PAINT MONO (-6150 4600);
DISPLAY INVISIBLE (-6150 4600);
FORCEPROP 1 LAST BODY_TYPE PLUMBING
J 0
(-6195 4557);
DISPLAY 0.340426 (-6195 4557);
PAINT GREEN (-6195 4557);
DISPLAY INVISIBLE (-6195 4557);
FORCEADD RES..2
(-6150 4400);
FORCEPROP 1 LAST LOCATION R7E6
J 0
(-6105 4525);
DISPLAY 0.617021 (-6105 4525);
PAINT AQUA (-6105 4525);
FORCEPROP 1 LAST PART_NUMBER G21796-016
J 0
(-6110 4275);
DISPLAY 0.617021 (-6110 4275);
PAINT BLUE (-6110 4275);
FORCEPROP 1 LAST VALUE 10.0K
J 0
(-6105 4475);
DISPLAY 0.617021 (-6105 4475);
PAINT SKYBLUE (-6105 4475);
FORCEPROP 1 LAST TOLERANCE 1%
J 0
(-6105 4425);
DISPLAY 0.617021 (-6105 4425);
PAINT SKYBLUE (-6105 4425);
FORCEPROP 1 LAST PACK_TYPE 0402
J 0
(-6110 4225);
DISPLAY 0.617021 (-6110 4225);
PAINT SKYBLUE (-6110 4225);
FORCEPROP 1 LAST MATERIAL CHIP
J 0
(-6110 4325);
DISPLAY 0.617021 (-6110 4325);
PAINT SKYBLUE (-6110 4325);
FORCEPROP 1 LAST WATTAGE 1/16W
J 0
(-6110 4375);
DISPLAY 0.617021 (-6110 4375);
PAINT SKYBLUE (-6110 4375);
FORCEPROP 1 LASTPIN (-6150 4500) $PN 1
J 0
(-6145 4462);
DISPLAY 0.787234 (-6145 4462);
PAINT ORANGE (-6145 4462);
DISPLAY INVISIBLE (-6145 4462);
FORCEPROP 1 LASTPIN (-6150 4300) $PN 2
J 0
(-6145 4310);
DISPLAY 0.787234 (-6145 4310);
PAINT ORANGE (-6145 4310);
DISPLAY INVISIBLE (-6145 4310);
FORCEPROP 2 LAST ROOM CPLD
J 0
(-6100 4575);
DISPLAY 1.021277 (-6100 4575);
PAINT ORANGE (-6100 4575);
DISPLAY INVISIBLE (-6100 4575);
FORCEPROP 2 LAST $SEC 1
J 0
(-6100 4625);
PAINT MONO (-6100 4625);
DISPLAY INVISIBLE (-6100 4625);
FORCEPROP 2 LAST CDS_SEC 1
J 0
(-6100 4625);
PAINT MONO (-6100 4625);
DISPLAY INVISIBLE (-6100 4625);
FORCEPROP 2 LAST BOM_COST CPLD
J 0
(-6100 4625);
DISPLAY 1.021277 (-6100 4625);
PAINT ORANGE (-6100 4625);
DISPLAY INVISIBLE (-6100 4625);
FORCEPROP 1 LAST PATH I33
J 0
(-6100 4575);
DISPLAY 0.978723 (-6100 4575);
PAINT WHITE (-6100 4575);
DISPLAY INVISIBLE (-6100 4575);
FORCEPROP 2 LAST CDS_LOCATION R7E6
J 0
(-6105 4525);
DISPLAY 0.617021 (-6105 4525);
PAINT AQUA (-6105 4525);
DISPLAY INVISIBLE (-6105 4525);
FORCEPROP 2 LAST CDS_LIB mstr_discrete
J 0
(-6150 4400);
PAINT MONO (-6150 4400);
DISPLAY INVISIBLE (-6150 4400);
FORCEADD RES..2
(-5750 4400);
FORCEPROP 1 LAST LOCATION R2R1
J 0
(-5705 4525);
DISPLAY 0.617021 (-5705 4525);
PAINT AQUA (-5705 4525);
FORCEPROP 1 LAST PART_NUMBER G21796-016
J 0
(-5710 4275);
DISPLAY 0.617021 (-5710 4275);
PAINT BLUE (-5710 4275);
FORCEPROP 1 LAST VALUE 10.0K
J 0
(-5705 4475);
DISPLAY 0.617021 (-5705 4475);
PAINT SKYBLUE (-5705 4475);
FORCEPROP 1 LAST TOLERANCE 1%
J 0
(-5705 4425);
DISPLAY 0.617021 (-5705 4425);
PAINT SKYBLUE (-5705 4425);
FORCEPROP 1 LAST PACK_TYPE 0402
J 0
(-5710 4225);
DISPLAY 0.617021 (-5710 4225);
PAINT SKYBLUE (-5710 4225);
FORCEPROP 1 LAST MATERIAL CHIP
J 0
(-5710 4325);
DISPLAY 0.617021 (-5710 4325);
PAINT SKYBLUE (-5710 4325);
FORCEPROP 1 LAST WATTAGE 1/16W
J 0
(-5710 4375);
DISPLAY 0.617021 (-5710 4375);
PAINT SKYBLUE (-5710 4375);
FORCEPROP 1 LASTPIN (-5750 4500) $PN 1
J 0
(-5745 4462);
DISPLAY 0.787234 (-5745 4462);
PAINT ORANGE (-5745 4462);
DISPLAY INVISIBLE (-5745 4462);
FORCEPROP 1 LASTPIN (-5750 4300) $PN 2
J 0
(-5745 4310);
DISPLAY 0.787234 (-5745 4310);
PAINT ORANGE (-5745 4310);
DISPLAY INVISIBLE (-5745 4310);
FORCEPROP 2 LAST ROOM CPLD
J 0
(-5700 4575);
DISPLAY 1.021277 (-5700 4575);
PAINT ORANGE (-5700 4575);
DISPLAY INVISIBLE (-5700 4575);
FORCEPROP 2 LAST $SEC 1
J 0
(-5700 4625);
PAINT MONO (-5700 4625);
DISPLAY INVISIBLE (-5700 4625);
FORCEPROP 2 LAST CDS_SEC 1
J 0
(-5700 4625);
PAINT MONO (-5700 4625);
DISPLAY INVISIBLE (-5700 4625);
FORCEPROP 2 LAST BOM_COST CPLD
J 0
(-5700 4625);
DISPLAY 1.021277 (-5700 4625);
PAINT ORANGE (-5700 4625);
DISPLAY INVISIBLE (-5700 4625);
FORCEPROP 1 LAST PATH I34
J 0
(-5700 4575);
DISPLAY 0.978723 (-5700 4575);
PAINT WHITE (-5700 4575);
DISPLAY INVISIBLE (-5700 4575);
FORCEPROP 2 LAST CDS_LOCATION R2R1
J 0
(-5705 4525);
DISPLAY 0.617021 (-5705 4525);
PAINT AQUA (-5705 4525);
DISPLAY INVISIBLE (-5705 4525);
FORCEPROP 2 LAST CDS_LIB mstr_discrete
J 0
(-5750 4400);
PAINT MONO (-5750 4400);
DISPLAY INVISIBLE (-5750 4400);
FORCEADD P3V3_STBY..1
(-5750 4600);
FORCEPROP 3 LASTPIN (-5750 4550) SIG_NAME P3V3_STBY\g
J 0
(-5740 4560);
DISPLAY 0.659574 (-5740 4560);
PAINT MONO (-5740 4560);
DISPLAY INVISIBLE (-5740 4560);
FORCEPROP 1 LAST VOLTAGE 3.3V
J 0
(-5795 4557);
DISPLAY 0.340426 (-5795 4557);
PAINT SKYBLUE (-5795 4557);
DISPLAY INVISIBLE (-5795 4557);
FORCEPROP 1 LAST HDL_POWER P3V3_STBY
J 0
(-6050 4475);
DISPLAY 0.872340 (-6050 4475);
PAINT ORANGE (-6050 4475);
DISPLAY INVISIBLE (-6050 4475);
FORCEPROP 1 LAST SIZE 1B
J 0
(-5705 4622);
DISPLAY 0.340426 (-5705 4622);
PAINT GREEN (-5705 4622);
DISPLAY INVISIBLE (-5705 4622);
FORCEPROP 1 LAST PATH I35
J 0
(-5705 4602);
DISPLAY 0.340426 (-5705 4602);
PAINT GREEN (-5705 4602);
DISPLAY INVISIBLE (-5705 4602);
FORCEPROP 2 LAST CDS_LIB mstr_symbols
J 0
(-5750 4600);
PAINT MONO (-5750 4600);
DISPLAY INVISIBLE (-5750 4600);
FORCEPROP 1 LAST BODY_TYPE PLUMBING
J 0
(-5795 4557);
DISPLAY 0.340426 (-5795 4557);
PAINT GREEN (-5795 4557);
DISPLAY INVISIBLE (-5795 4557);
FORCEADD OFFPAGE..2
(-5100 4200);
FORCEPROP 2 LASTPIN (-5150 4200) SIG_NAME PU_RST_PERST_BIT0
J 2
(-5160 4210);
DISPLAY 0.617021 (-5160 4210);
PAINT ORANGE (-5160 4210);
FORCEPROP 2 LAST $XR0 190 
J 0
(-4911 4200);
DISPLAY 0.638298 (-4911 4200);
PAINT MONO (-4911 4200);
FORCEPROP 1 LAST OFFPAGE TRUE
J 0
(-4775 4075);
DISPLAY 0.872340 (-4775 4075);
PAINT GREEN (-4775 4075);
DISPLAY INVISIBLE (-4775 4075);
FORCEPROP 1 LAST COMMENT_BODY TRUE
J 0
(-5145 4105);
DISPLAY 0.872340 (-5145 4105);
PAINT GREEN (-5145 4105);
DISPLAY INVISIBLE (-5145 4105);
FORCEPROP 2 LAST CDS_LIB mstr_standard
J 0
(-5100 4200);
PAINT MONO (-5100 4200);
DISPLAY INVISIBLE (-5100 4200);
FORCEPROP 2 LAST PATH I36
J 0
(-4925 4275);
DISPLAY 1.021277 (-4925 4275);
PAINT ORANGE (-4925 4275);
DISPLAY INVISIBLE (-4925 4275);
FORCEADD OFFPAGE..2
(-5100 4100);
FORCEPROP 2 LASTPIN (-5150 4100) SIG_NAME PU_RST_PERST_BIT1
J 2
(-5160 4110);
DISPLAY 0.617021 (-5160 4110);
PAINT ORANGE (-5160 4110);
FORCEPROP 2 LAST $XR0 191 
J 0
(-4911 4100);
DISPLAY 0.638298 (-4911 4100);
PAINT MONO (-4911 4100);
FORCEPROP 1 LAST COMMENT_BODY TRUE
J 0
(-5145 4005);
DISPLAY 0.872340 (-5145 4005);
PAINT GREEN (-5145 4005);
DISPLAY INVISIBLE (-5145 4005);
FORCEPROP 1 LAST OFFPAGE TRUE
J 0
(-4775 3975);
DISPLAY 0.872340 (-4775 3975);
PAINT GREEN (-4775 3975);
DISPLAY INVISIBLE (-4775 3975);
FORCEPROP 2 LAST CDS_LIB mstr_standard
J 0
(-5100 4100);
PAINT MONO (-5100 4100);
DISPLAY INVISIBLE (-5100 4100);
FORCEPROP 2 LAST PATH I37
J 0
(-4925 4175);
DISPLAY 1.021277 (-4925 4175);
PAINT ORANGE (-4925 4175);
DISPLAY INVISIBLE (-4925 4175);
FORCEADD RES..2
(-6550 4400);
FORCEPROP 1 LAST LOCATION R7E5
J 0
(-6505 4525);
DISPLAY 0.617021 (-6505 4525);
PAINT AQUA (-6505 4525);
FORCEPROP 1 LAST PART_NUMBER G21796-016
J 0
(-6510 4275);
DISPLAY 0.617021 (-6510 4275);
PAINT BLUE (-6510 4275);
FORCEPROP 1 LAST VALUE 10.0K
J 0
(-6505 4475);
DISPLAY 0.617021 (-6505 4475);
PAINT SKYBLUE (-6505 4475);
FORCEPROP 1 LAST TOLERANCE 1%
J 0
(-6505 4425);
DISPLAY 0.617021 (-6505 4425);
PAINT SKYBLUE (-6505 4425);
FORCEPROP 1 LAST PACK_TYPE 0402
J 0
(-6510 4225);
DISPLAY 0.617021 (-6510 4225);
PAINT SKYBLUE (-6510 4225);
FORCEPROP 1 LAST MATERIAL CHIP
J 0
(-6510 4325);
DISPLAY 0.617021 (-6510 4325);
PAINT SKYBLUE (-6510 4325);
FORCEPROP 1 LAST WATTAGE 1/16W
J 0
(-6510 4375);
DISPLAY 0.617021 (-6510 4375);
PAINT SKYBLUE (-6510 4375);
FORCEPROP 1 LASTPIN (-6550 4500) $PN 1
J 0
(-6545 4462);
DISPLAY 0.617021 (-6545 4462);
PAINT ORANGE (-6545 4462);
FORCEPROP 1 LASTPIN (-6550 4300) $PN 2
J 0
(-6545 4310);
DISPLAY 0.617021 (-6545 4310);
PAINT ORANGE (-6545 4310);
FORCEPROP 2 LAST ROOM CPLD
J 0
(-6500 4575);
DISPLAY 1.021277 (-6500 4575);
PAINT ORANGE (-6500 4575);
DISPLAY INVISIBLE (-6500 4575);
FORCEPROP 2 LAST $SEC 1
J 0
(-6500 4625);
PAINT MONO (-6500 4625);
DISPLAY INVISIBLE (-6500 4625);
FORCEPROP 2 LAST CDS_SEC 1
J 0
(-6500 4625);
PAINT MONO (-6500 4625);
DISPLAY INVISIBLE (-6500 4625);
FORCEPROP 2 LAST BOM_COST CPLD
J 0
(-6500 4625);
DISPLAY 1.021277 (-6500 4625);
PAINT ORANGE (-6500 4625);
DISPLAY INVISIBLE (-6500 4625);
FORCEPROP 1 LAST PATH I38
J 0
(-6500 4575);
DISPLAY 0.978723 (-6500 4575);
PAINT WHITE (-6500 4575);
DISPLAY INVISIBLE (-6500 4575);
FORCEPROP 2 LAST CDS_LOCATION R7E5
J 0
(-6505 4525);
DISPLAY 0.617021 (-6505 4525);
PAINT AQUA (-6505 4525);
DISPLAY INVISIBLE (-6505 4525);
FORCEPROP 2 LAST CDS_LIB mstr_discrete
J 0
(-6550 4400);
PAINT MONO (-6550 4400);
DISPLAY INVISIBLE (-6550 4400);
FORCEADD P3V3_STBY..1
(-6550 4600);
FORCEPROP 3 LASTPIN (-6550 4550) SIG_NAME P3V3_STBY\g
J 0
(-6540 4560);
DISPLAY 0.659574 (-6540 4560);
PAINT MONO (-6540 4560);
DISPLAY INVISIBLE (-6540 4560);
FORCEPROP 1 LAST VOLTAGE 3.3V
J 0
(-6595 4557);
DISPLAY 0.340426 (-6595 4557);
PAINT SKYBLUE (-6595 4557);
DISPLAY INVISIBLE (-6595 4557);
FORCEPROP 1 LAST HDL_POWER P3V3_STBY
J 0
(-6850 4475);
DISPLAY 0.872340 (-6850 4475);
PAINT ORANGE (-6850 4475);
DISPLAY INVISIBLE (-6850 4475);
FORCEPROP 1 LAST SIZE 1B
J 0
(-6505 4622);
DISPLAY 0.340426 (-6505 4622);
PAINT GREEN (-6505 4622);
DISPLAY INVISIBLE (-6505 4622);
FORCEPROP 1 LAST PATH I39
J 0
(-6505 4602);
DISPLAY 0.340426 (-6505 4602);
PAINT GREEN (-6505 4602);
DISPLAY INVISIBLE (-6505 4602);
FORCEPROP 2 LAST CDS_LIB mstr_symbols
J 0
(-6550 4600);
PAINT MONO (-6550 4600);
DISPLAY INVISIBLE (-6550 4600);
FORCEPROP 1 LAST BODY_TYPE PLUMBING
J 0
(-6595 4557);
DISPLAY 0.340426 (-6595 4557);
PAINT GREEN (-6595 4557);
DISPLAY INVISIBLE (-6595 4557);
FORCEADD CAP_A..1
(-2175 1975);
FORCEPROP 1 LAST LOCATION C3R1
J 0
(-2125 2075);
DISPLAY 0.617021 (-2125 2075);
PAINT AQUA (-2125 2075);
FORCEPROP 1 LAST PART_NUMBER A36096-030
J 0
(-2125 1825);
DISPLAY 0.617021 (-2125 1825);
PAINT BLUE (-2125 1825);
FORCEPROP 1 LAST VALUE 0.1UF
J 0
(-2125 2025);
DISPLAY 0.617021 (-2125 2025);
PAINT SKYBLUE (-2125 2025);
FORCEPROP 1 LAST TOLERANCE 10%
J 0
(-2125 1925);
DISPLAY 0.617021 (-2125 1925);
PAINT SKYBLUE (-2125 1925);
FORCEPROP 1 LAST PACK_TYPE 0402V
J 0
(-2125 1775);
DISPLAY 0.617021 (-2125 1775);
PAINT SKYBLUE (-2125 1775);
FORCEPROP 1 LAST VOLTAGE 16V
J 0
(-2125 1975);
DISPLAY 0.617021 (-2125 1975);
PAINT SKYBLUE (-2125 1975);
FORCEPROP 1 LAST MATERIAL X7R
J 0
(-2125 1875);
DISPLAY 0.617021 (-2125 1875);
PAINT SKYBLUE (-2125 1875);
FORCEPROP 1 LASTPIN (-2175 2075) $PN 1
J 0
(-2165 2055);
DISPLAY 0.617021 (-2165 2055);
PAINT ORANGE (-2165 2055);
FORCEPROP 1 LASTPIN (-2175 1875) $PN 2
J 0
(-2165 1855);
DISPLAY 0.617021 (-2165 1855);
PAINT ORANGE (-2165 1855);
FORCEPROP 2 LAST ROOM CPLD
J 0
(-2125 2125);
DISPLAY 1.361702 (-2125 2125);
PAINT ORANGE (-2125 2125);
DISPLAY INVISIBLE (-2125 2125);
FORCEPROP 2 LAST CDS_SEC 1
J 0
(-2125 2175);
PAINT MONO (-2125 2175);
DISPLAY INVISIBLE (-2125 2175);
FORCEPROP 2 LAST BOM_COST CPLD
J 0
(-2125 2175);
DISPLAY 1.361702 (-2125 2175);
PAINT ORANGE (-2125 2175);
DISPLAY INVISIBLE (-2125 2175);
FORCEPROP 2 LAST $SEC 1
J 0
(-2125 2175);
PAINT MONO (-2125 2175);
DISPLAY INVISIBLE (-2125 2175);
FORCEPROP 2 LAST SIGNAL_MODEL DEFAULT_CAPACITOR_100000pF_2_1
J 0
(-2125 2175);
PAINT MONO (-2125 2175);
DISPLAY INVISIBLE (-2125 2175);
FORCEPROP 2 LAST CDS_LOCATION C3R1
J 0
(-2125 2075);
DISPLAY 0.617021 (-2125 2075);
PAINT AQUA (-2125 2075);
DISPLAY INVISIBLE (-2125 2075);
FORCEPROP 1 LAST PATH I4
J 0
(-2125 2125);
DISPLAY 0.978723 (-2125 2125);
PAINT WHITE (-2125 2125);
DISPLAY INVISIBLE (-2125 2125);
FORCEPROP 2 LAST CDS_LIB dev_discrete
J 0
(-2175 1975);
PAINT ORANGE (-2175 1975);
DISPLAY INVISIBLE (-2175 1975);
FORCEADD OFFPAGE..2
(-5100 4000);
FORCEPROP 2 LASTPIN (-5150 4000) SIG_NAME PU_THERMTRIP_FORCE_N
J 2
(-5160 4010);
DISPLAY 0.617021 (-5160 4010);
PAINT ORANGE (-5160 4010);
FORCEPROP 2 LAST $XR0 191 
J 0
(-4911 4000);
DISPLAY 0.638298 (-4911 4000);
PAINT MONO (-4911 4000);
FORCEPROP 1 LAST COMMENT_BODY TRUE
J 0
(-5145 3905);
DISPLAY 0.872340 (-5145 3905);
PAINT GREEN (-5145 3905);
DISPLAY INVISIBLE (-5145 3905);
FORCEPROP 2 LAST CDS_LIB mstr_standard
J 0
(-5100 4000);
PAINT MONO (-5100 4000);
DISPLAY INVISIBLE (-5100 4000);
FORCEPROP 1 LAST OFFPAGE TRUE
J 0
(-4775 3875);
DISPLAY 0.872340 (-4775 3875);
PAINT GREEN (-4775 3875);
DISPLAY INVISIBLE (-4775 3875);
FORCEPROP 2 LAST PATH I40
J 0
(-4925 4075);
DISPLAY 1.021277 (-4925 4075);
PAINT ORANGE (-4925 4075);
DISPLAY INVISIBLE (-4925 4075);
FORCEADD RES..2
(-6950 4400);
FORCEPROP 1 LAST LOCATION R2R3
J 0
(-6905 4525);
DISPLAY 0.617021 (-6905 4525);
PAINT AQUA (-6905 4525);
FORCEPROP 1 LAST PART_NUMBER G21796-016
J 0
(-6910 4275);
DISPLAY 0.617021 (-6910 4275);
PAINT BLUE (-6910 4275);
FORCEPROP 1 LAST VALUE 10.0K
J 0
(-6905 4475);
DISPLAY 0.617021 (-6905 4475);
PAINT SKYBLUE (-6905 4475);
FORCEPROP 1 LAST TOLERANCE 1%
J 0
(-6905 4425);
DISPLAY 0.617021 (-6905 4425);
PAINT SKYBLUE (-6905 4425);
FORCEPROP 1 LAST PACK_TYPE 0402
J 0
(-6910 4225);
DISPLAY 0.617021 (-6910 4225);
PAINT SKYBLUE (-6910 4225);
FORCEPROP 1 LAST MATERIAL CHIP
J 0
(-6910 4325);
DISPLAY 0.617021 (-6910 4325);
PAINT SKYBLUE (-6910 4325);
FORCEPROP 1 LAST WATTAGE 1/16W
J 0
(-6910 4375);
DISPLAY 0.617021 (-6910 4375);
PAINT SKYBLUE (-6910 4375);
FORCEPROP 1 LASTPIN (-6950 4500) $PN 1
J 0
(-6945 4462);
DISPLAY 0.617021 (-6945 4462);
PAINT ORANGE (-6945 4462);
FORCEPROP 1 LASTPIN (-6950 4300) $PN 2
J 0
(-6945 4310);
DISPLAY 0.617021 (-6945 4310);
PAINT ORANGE (-6945 4310);
FORCEPROP 2 LAST ROOM CPLD
J 0
(-6900 4575);
DISPLAY 1.021277 (-6900 4575);
PAINT ORANGE (-6900 4575);
DISPLAY INVISIBLE (-6900 4575);
FORCEPROP 2 LAST $SEC 1
J 0
(-6900 4625);
PAINT MONO (-6900 4625);
DISPLAY INVISIBLE (-6900 4625);
FORCEPROP 2 LAST CDS_SEC 1
J 0
(-6900 4625);
PAINT MONO (-6900 4625);
DISPLAY INVISIBLE (-6900 4625);
FORCEPROP 2 LAST BOM_COST CPLD
J 0
(-6900 4625);
DISPLAY 1.021277 (-6900 4625);
PAINT ORANGE (-6900 4625);
DISPLAY INVISIBLE (-6900 4625);
FORCEPROP 1 LAST PATH I41
J 0
(-6900 4575);
DISPLAY 0.978723 (-6900 4575);
PAINT WHITE (-6900 4575);
DISPLAY INVISIBLE (-6900 4575);
FORCEPROP 2 LAST CDS_LOCATION R2R3
J 0
(-6905 4525);
DISPLAY 0.617021 (-6905 4525);
PAINT AQUA (-6905 4525);
DISPLAY INVISIBLE (-6905 4525);
FORCEPROP 2 LAST CDS_LIB mstr_discrete
J 0
(-6950 4400);
PAINT MONO (-6950 4400);
DISPLAY INVISIBLE (-6950 4400);
FORCEADD P3V3_STBY..1
(-6950 4600);
FORCEPROP 3 LASTPIN (-6950 4550) SIG_NAME P3V3_STBY\g
J 0
(-6940 4560);
DISPLAY 0.659574 (-6940 4560);
PAINT MONO (-6940 4560);
DISPLAY INVISIBLE (-6940 4560);
FORCEPROP 1 LAST VOLTAGE 3.3V
J 0
(-6995 4557);
DISPLAY 0.340426 (-6995 4557);
PAINT SKYBLUE (-6995 4557);
DISPLAY INVISIBLE (-6995 4557);
FORCEPROP 1 LAST HDL_POWER P3V3_STBY
J 0
(-7250 4475);
DISPLAY 0.872340 (-7250 4475);
PAINT ORANGE (-7250 4475);
DISPLAY INVISIBLE (-7250 4475);
FORCEPROP 1 LAST SIZE 1B
J 0
(-6905 4622);
DISPLAY 0.340426 (-6905 4622);
PAINT GREEN (-6905 4622);
DISPLAY INVISIBLE (-6905 4622);
FORCEPROP 1 LAST PATH I42
J 0
(-6905 4602);
DISPLAY 0.340426 (-6905 4602);
PAINT GREEN (-6905 4602);
DISPLAY INVISIBLE (-6905 4602);
FORCEPROP 2 LAST CDS_LIB mstr_symbols
J 0
(-6950 4600);
PAINT MONO (-6950 4600);
DISPLAY INVISIBLE (-6950 4600);
FORCEPROP 1 LAST BODY_TYPE PLUMBING
J 0
(-6995 4557);
DISPLAY 0.340426 (-6995 4557);
PAINT GREEN (-6995 4557);
DISPLAY INVISIBLE (-6995 4557);
FORCEADD OFFPAGE..2
(-5100 3900);
FORCEPROP 2 LASTPIN (-5150 3900) SIG_NAME FM_PLD_DEBUG_MODE_N
J 2
(-5160 3910);
DISPLAY 0.617021 (-5160 3910);
PAINT ORANGE (-5160 3910);
FORCEPROP 2 LAST $XR0 191 
J 0
(-4911 3900);
DISPLAY 0.638298 (-4911 3900);
PAINT MONO (-4911 3900);
FORCEPROP 1 LAST COMMENT_BODY TRUE
J 0
(-5145 3805);
DISPLAY 0.872340 (-5145 3805);
PAINT GREEN (-5145 3805);
DISPLAY INVISIBLE (-5145 3805);
FORCEPROP 2 LAST CDS_LIB mstr_standard
J 0
(-5100 3900);
PAINT MONO (-5100 3900);
DISPLAY INVISIBLE (-5100 3900);
FORCEPROP 2 LAST PATH I45
J 0
(-4925 3975);
DISPLAY 1.021277 (-4925 3975);
PAINT ORANGE (-4925 3975);
DISPLAY INVISIBLE (-4925 3975);
FORCEPROP 1 LAST OFFPAGE TRUE
J 0
(-4775 3775);
DISPLAY 0.872340 (-4775 3775);
PAINT GREEN (-4775 3775);
DISPLAY INVISIBLE (-4775 3775);
FORCEADD RES..2
(-6150 2800);
FORCEPROP 1 LAST LOCATION R3R16
J 0
(-6105 2925);
DISPLAY 0.617021 (-6105 2925);
PAINT AQUA (-6105 2925);
FORCEPROP 1 LAST PART_NUMBER G21796-072
J 0
(-6110 2675);
DISPLAY 0.617021 (-6110 2675);
PAINT BLUE (-6110 2675);
FORCEPROP 1 LAST VALUE 4.75K
J 0
(-6105 2875);
DISPLAY 0.617021 (-6105 2875);
PAINT SKYBLUE (-6105 2875);
FORCEPROP 1 LAST TOLERANCE 1%
J 0
(-6105 2825);
DISPLAY 0.617021 (-6105 2825);
PAINT SKYBLUE (-6105 2825);
FORCEPROP 1 LAST PACK_TYPE 0402
J 0
(-6110 2625);
DISPLAY 0.617021 (-6110 2625);
PAINT SKYBLUE (-6110 2625);
FORCEPROP 1 LAST WATTAGE 1/16W
J 0
(-6110 2775);
DISPLAY 0.617021 (-6110 2775);
PAINT SKYBLUE (-6110 2775);
FORCEPROP 1 LASTPIN (-6150 2900) $PN 1
J 0
(-6145 2862);
DISPLAY 0.617021 (-6145 2862);
PAINT ORANGE (-6145 2862);
FORCEPROP 1 LASTPIN (-6150 2700) $PN 2
J 0
(-6145 2710);
DISPLAY 0.617021 (-6145 2710);
PAINT ORANGE (-6145 2710);
FORCEPROP 1 LAST MATERIAL CHIP
J 0
(-6110 2725);
DISPLAY 0.617021 (-6110 2725);
PAINT SKYBLUE (-6110 2725);
FORCEPROP 0 LAST ROOM CPLD
J 0
(-6100 3025);
DISPLAY 1.021277 (-6100 3025);
PAINT ORANGE (-6100 3025);
DISPLAY INVISIBLE (-6100 3025);
FORCEPROP 0 LAST BOM_COST CPLD
J 0
(-6100 3125);
DISPLAY 1.021277 (-6100 3125);
PAINT ORANGE (-6100 3125);
DISPLAY INVISIBLE (-6100 3125);
FORCEPROP 1 LAST PATH I48
J 0
(-6100 2975);
DISPLAY 0.978723 (-6100 2975);
PAINT WHITE (-6100 2975);
DISPLAY INVISIBLE (-6100 2975);
FORCEPROP 2 LAST SEC 1
J 0
(-6100 3025);
DISPLAY 0.680851 (-6100 3025);
PAINT MONO (-6100 3025);
DISPLAY INVISIBLE (-6100 3025);
FORCEPROP 2 LAST SEC_TYPE 0402
J 0
(-6100 3025);
DISPLAY 1.021277 (-6100 3025);
PAINT ORANGE (-6100 3025);
DISPLAY INVISIBLE (-6100 3025);
FORCEPROP 2 LAST CDS_LIB mstr_discrete
J 0
(-6150 2800);
PAINT ORANGE (-6150 2800);
DISPLAY INVISIBLE (-6150 2800);
FORCEADD RES..2
(-5750 2800);
FORCEPROP 1 LAST LOCATION R6M9
J 0
(-5705 2925);
DISPLAY 0.617021 (-5705 2925);
PAINT AQUA (-5705 2925);
FORCEPROP 1 LAST PART_NUMBER G21796-072
J 0
(-5710 2675);
DISPLAY 0.617021 (-5710 2675);
PAINT BLUE (-5710 2675);
FORCEPROP 1 LAST VALUE 4.75K
J 0
(-5705 2875);
DISPLAY 0.617021 (-5705 2875);
PAINT SKYBLUE (-5705 2875);
FORCEPROP 1 LAST TOLERANCE 1%
J 0
(-5705 2825);
DISPLAY 0.617021 (-5705 2825);
PAINT SKYBLUE (-5705 2825);
FORCEPROP 1 LAST PACK_TYPE 0402
J 0
(-5710 2625);
DISPLAY 0.617021 (-5710 2625);
PAINT SKYBLUE (-5710 2625);
FORCEPROP 1 LAST MATERIAL CHIP
J 0
(-5710 2725);
DISPLAY 0.617021 (-5710 2725);
PAINT SKYBLUE (-5710 2725);
FORCEPROP 1 LAST WATTAGE 1/16W
J 0
(-5710 2775);
DISPLAY 0.617021 (-5710 2775);
PAINT SKYBLUE (-5710 2775);
FORCEPROP 1 LASTPIN (-5750 2900) $PN 1
J 0
(-5745 2862);
DISPLAY 0.617021 (-5745 2862);
PAINT ORANGE (-5745 2862);
FORCEPROP 1 LASTPIN (-5750 2700) $PN 2
J 0
(-5745 2710);
DISPLAY 0.617021 (-5745 2710);
PAINT ORANGE (-5745 2710);
FORCEPROP 2 LAST ROOM CPLD
J 0
(-5700 2975);
DISPLAY 1.021277 (-5700 2975);
PAINT ORANGE (-5700 2975);
DISPLAY INVISIBLE (-5700 2975);
FORCEPROP 2 LAST SEC 1
J 0
(-5700 3025);
DISPLAY 0.680851 (-5700 3025);
PAINT MONO (-5700 3025);
DISPLAY INVISIBLE (-5700 3025);
FORCEPROP 2 LAST SEC_TYPE 0402
J 0
(-5700 3025);
DISPLAY 1.021277 (-5700 3025);
PAINT ORANGE (-5700 3025);
DISPLAY INVISIBLE (-5700 3025);
FORCEPROP 1 LAST PATH I49
J 0
(-5700 2975);
DISPLAY 0.978723 (-5700 2975);
PAINT WHITE (-5700 2975);
DISPLAY INVISIBLE (-5700 2975);
FORCEPROP 2 LAST BOM_COST CPLD
J 0
(-5700 3025);
DISPLAY 1.021277 (-5700 3025);
PAINT ORANGE (-5700 3025);
DISPLAY INVISIBLE (-5700 3025);
FORCEPROP 2 LAST CDS_LIB mstr_discrete
J 0
(-5750 2800);
PAINT ORANGE (-5750 2800);
DISPLAY INVISIBLE (-5750 2800);
FORCEADD GND..1
(-1100 3100);
FORCEPROP 3 LASTPIN (-1100 3150) SIG_NAME GND\g
J 0
(-1090 3160);
DISPLAY 0.659574 (-1090 3160);
PAINT MONO (-1090 3160);
DISPLAY INVISIBLE (-1090 3160);
FORCEPROP 1 LAST VOLTAGE 0.0V
J 0
(-1145 3057);
DISPLAY 0.340426 (-1145 3057);
PAINT SKYBLUE (-1145 3057);
DISPLAY INVISIBLE (-1145 3057);
FORCEPROP 1 LAST HDL_POWER GND
J 0
(-1100 3250);
DISPLAY 1.170213 (-1100 3250);
PAINT GREEN (-1100 3250);
DISPLAY INVISIBLE (-1100 3250);
FORCEPROP 2 LAST ROOM CPLD
J 0
(-1325 3175);
DISPLAY 1.361702 (-1325 3175);
PAINT ORANGE (-1325 3175);
DISPLAY INVISIBLE (-1325 3175);
FORCEPROP 2 LAST CDS_LIB mstr_symbols
J 0
(-1100 3100);
PAINT ORANGE (-1100 3100);
DISPLAY INVISIBLE (-1100 3100);
FORCEPROP 1 LAST PATH I5
J 0
(-1025 3100);
DISPLAY 0.872340 (-1025 3100);
PAINT AQUA (-1025 3100);
DISPLAY INVISIBLE (-1025 3100);
FORCEPROP 2 LAST BOM_COST CPLD
J 0
(-1325 3225);
DISPLAY 1.361702 (-1325 3225);
PAINT ORANGE (-1325 3225);
DISPLAY INVISIBLE (-1325 3225);
FORCEPROP 1 LAST SIZE 1B
J 0
(-1025 3050);
DISPLAY 1.170213 (-1025 3050);
PAINT AQUA (-1025 3050);
DISPLAY INVISIBLE (-1025 3050);
FORCEPROP 1 LAST BODY_TYPE PLUMBING
J 0
(-1145 3057);
DISPLAY 0.340426 (-1145 3057);
PAINT GREEN (-1145 3057);
DISPLAY INVISIBLE (-1145 3057);
FORCEADD OFFPAGE..2
(-5100 2500);
FORCEPROP 2 LASTPIN (-5150 2500) SIG_NAME RST_CD_CPU0_POR_N
J 2
(-5160 2510);
DISPLAY 0.617021 (-5160 2510);
PAINT ORANGE (-5160 2510);
FORCEPROP 2 LAST $XR0 190 
J 0
(-4911 2500);
DISPLAY 0.638298 (-4911 2500);
PAINT MONO (-4911 2500);
FORCEPROP 2 LAST $XR1 29 
J 0
(-4791 2500);
DISPLAY 0.638298 (-4791 2500);
PAINT MONO (-4791 2500);
FORCEPROP 1 LAST COMMENT_BODY TRUE
J 0
(-5145 2405);
DISPLAY 0.872340 (-5145 2405);
PAINT GREEN (-5145 2405);
DISPLAY INVISIBLE (-5145 2405);
FORCEPROP 2 LAST CDS_LIB mstr_standard
J 0
(-5100 2500);
PAINT ORANGE (-5100 2500);
DISPLAY INVISIBLE (-5100 2500);
FORCEPROP 1 LAST OFFPAGE TRUE
J 0
(-4775 2375);
DISPLAY 0.872340 (-4775 2375);
PAINT GREEN (-4775 2375);
DISPLAY INVISIBLE (-4775 2375);
FORCEPROP 2 LAST PATH I50
J 0
(-4925 2575);
DISPLAY 1.021277 (-4925 2575);
PAINT ORANGE (-4925 2575);
DISPLAY INVISIBLE (-4925 2575);
FORCEADD OFFPAGE..2
(-5100 2600);
FORCEPROP 2 LASTPIN (-5150 2600) SIG_NAME RST_CD_CPU1_POR_N
J 2
(-5160 2610);
DISPLAY 0.617021 (-5160 2610);
PAINT ORANGE (-5160 2610);
FORCEPROP 2 LAST $XR1 63 
J 0
(-4791 2600);
DISPLAY 0.638298 (-4791 2600);
PAINT MONO (-4791 2600);
FORCEPROP 2 LAST $XR0 190 
J 0
(-4911 2600);
DISPLAY 0.638298 (-4911 2600);
PAINT MONO (-4911 2600);
FORCEPROP 1 LAST COMMENT_BODY TRUE
J 0
(-5145 2505);
DISPLAY 0.872340 (-5145 2505);
PAINT GREEN (-5145 2505);
DISPLAY INVISIBLE (-5145 2505);
FORCEPROP 1 LAST OFFPAGE TRUE
J 0
(-4775 2475);
DISPLAY 0.872340 (-4775 2475);
PAINT GREEN (-4775 2475);
DISPLAY INVISIBLE (-4775 2475);
FORCEPROP 2 LAST CDS_LIB mstr_standard
J 0
(-5100 2600);
PAINT ORANGE (-5100 2600);
DISPLAY INVISIBLE (-5100 2600);
FORCEPROP 2 LAST PATH I51
J 0
(-4925 2675);
DISPLAY 1.021277 (-4925 2675);
PAINT ORANGE (-4925 2675);
DISPLAY INVISIBLE (-4925 2675);
FORCEADD PVPP_ABC..1
(-6150 3000);
FORCEPROP 3 LASTPIN (-6150 2950) SIG_NAME PVPP_ABC\g
J 0
(-6140 2960);
DISPLAY 0.659574 (-6140 2960);
PAINT MONO (-6140 2960);
DISPLAY INVISIBLE (-6140 2960);
FORCEPROP 1 LAST VOLTAGE 2.5V
J 0
(-6195 2957);
DISPLAY 0.340426 (-6195 2957);
PAINT SKYBLUE (-6195 2957);
DISPLAY INVISIBLE (-6195 2957);
FORCEPROP 1 LAST HDL_POWER PVPP_ABC
J 1
(-6150 3050);
DISPLAY 0.872340 (-6150 3050);
PAINT GREEN (-6150 3050);
DISPLAY INVISIBLE (-6150 3050);
FORCEPROP 2 LAST ROOM PVPP_KLM_VR
J 0
(-5900 3100);
PAINT ORANGE (-5900 3100);
DISPLAY INVISIBLE (-5900 3100);
FORCEPROP 2 LAST BOM_COST PVPP_KLM_VR
J 0
(-6075 3100);
PAINT MONO (-6075 3100);
DISPLAY INVISIBLE (-6075 3100);
FORCEPROP 1 LAST PATH I52
J 0
(-6100 3025);
DISPLAY 0.872340 (-6100 3025);
PAINT AQUA (-6100 3025);
DISPLAY INVISIBLE (-6100 3025);
FORCEPROP 2 LAST CDS_LIB mstr_symbols
J 0
(-6150 3000);
PAINT ORANGE (-6150 3000);
DISPLAY INVISIBLE (-6150 3000);
FORCEPROP 1 LAST BODY_TYPE PLUMBING
J 0
(-6195 2957);
DISPLAY 0.340426 (-6195 2957);
PAINT GREEN (-6195 2957);
DISPLAY INVISIBLE (-6195 2957);
FORCEADD OFFPAGE..2
(-5100 3800);
FORCEPROP 2 LASTPIN (-5150 3800) SIG_NAME RST_RSMRST_N
J 2
(-5160 3810);
DISPLAY 0.617021 (-5160 3810);
PAINT ORANGE (-5160 3810);
FORCEPROP 2 LAST $XR0 190 
J 0
(-4911 3800);
DISPLAY 0.638298 (-4911 3800);
PAINT MONO (-4911 3800);
FORCEPROP 2 LAST $XR1 111 
J 0
(-4791 3800);
DISPLAY 0.638298 (-4791 3800);
PAINT MONO (-4791 3800);
FORCEPROP 2 LAST $XR2 118 
J 0
(-4671 3800);
DISPLAY 0.638298 (-4671 3800);
PAINT MONO (-4671 3800);
FORCEPROP 1 LAST COMMENT_BODY TRUE
J 0
(-5145 3705);
DISPLAY 0.872340 (-5145 3705);
PAINT GREEN (-5145 3705);
DISPLAY INVISIBLE (-5145 3705);
FORCEPROP 2 LAST CDS_LIB mstr_standard
J 0
(-5100 3800);
PAINT ORANGE (-5100 3800);
DISPLAY INVISIBLE (-5100 3800);
FORCEPROP 2 LAST PATH I54
J 0
(-4925 3875);
DISPLAY 1.021277 (-4925 3875);
PAINT ORANGE (-4925 3875);
DISPLAY INVISIBLE (-4925 3875);
FORCEPROP 1 LAST OFFPAGE TRUE
J 0
(-4775 3675);
DISPLAY 0.872340 (-4775 3675);
PAINT GREEN (-4775 3675);
DISPLAY INVISIBLE (-4775 3675);
FORCEADD RES..2
(-7350 4400);
FORCEPROP 1 LAST LOCATION R7E18
J 0
(-7305 4525);
DISPLAY 0.617021 (-7305 4525);
PAINT AQUA (-7305 4525);
FORCEPROP 1 LAST PART_NUMBER G21796-072
J 0
(-7310 4275);
DISPLAY 0.617021 (-7310 4275);
PAINT BLUE (-7310 4275);
FORCEPROP 1 LAST VALUE 4.75K
J 0
(-7305 4475);
DISPLAY 0.617021 (-7305 4475);
PAINT SKYBLUE (-7305 4475);
FORCEPROP 1 LAST TOLERANCE 1%
J 0
(-7305 4425);
DISPLAY 0.617021 (-7305 4425);
PAINT SKYBLUE (-7305 4425);
FORCEPROP 1 LAST PACK_TYPE 0402
J 0
(-7310 4225);
DISPLAY 0.617021 (-7310 4225);
PAINT SKYBLUE (-7310 4225);
FORCEPROP 1 LAST MATERIAL CHIP
J 0
(-7310 4325);
DISPLAY 0.617021 (-7310 4325);
PAINT SKYBLUE (-7310 4325);
FORCEPROP 1 LAST WATTAGE 1/16W
J 0
(-7310 4375);
DISPLAY 0.617021 (-7310 4375);
PAINT SKYBLUE (-7310 4375);
FORCEPROP 1 LASTPIN (-7350 4500) $PN 1
J 0
(-7345 4462);
DISPLAY 0.787234 (-7345 4462);
PAINT ORANGE (-7345 4462);
DISPLAY INVISIBLE (-7345 4462);
FORCEPROP 1 LASTPIN (-7350 4300) $PN 2
J 0
(-7345 4310);
DISPLAY 0.787234 (-7345 4310);
PAINT ORANGE (-7345 4310);
DISPLAY INVISIBLE (-7345 4310);
FORCEPROP 0 LAST ROOM CPLD
J 0
(-7300 4625);
DISPLAY 1.021277 (-7300 4625);
PAINT ORANGE (-7300 4625);
DISPLAY INVISIBLE (-7300 4625);
FORCEPROP 2 LAST $SEC 1
J 0
(-7300 4625);
PAINT MONO (-7300 4625);
DISPLAY INVISIBLE (-7300 4625);
FORCEPROP 2 LAST CDS_SEC 1
J 0
(-7300 4625);
PAINT MONO (-7300 4625);
DISPLAY INVISIBLE (-7300 4625);
FORCEPROP 0 LAST BOM_COST CPLD
J 0
(-7300 4725);
DISPLAY 1.021277 (-7300 4725);
PAINT ORANGE (-7300 4725);
DISPLAY INVISIBLE (-7300 4725);
FORCEPROP 1 LAST PATH I55
J 0
(-7300 4575);
DISPLAY 0.978723 (-7300 4575);
PAINT WHITE (-7300 4575);
DISPLAY INVISIBLE (-7300 4575);
FORCEPROP 2 LAST CDS_LIB mstr_discrete
J 0
(-7350 4400);
PAINT ORANGE (-7350 4400);
DISPLAY INVISIBLE (-7350 4400);
FORCEADD P3V3_STBY..1
(-7350 4600);
FORCEPROP 3 LASTPIN (-7350 4550) SIG_NAME P3V3_STBY\g
J 0
(-7340 4560);
DISPLAY 0.659574 (-7340 4560);
PAINT MONO (-7340 4560);
DISPLAY INVISIBLE (-7340 4560);
FORCEPROP 1 LAST VOLTAGE 3.3V
J 0
(-7395 4557);
DISPLAY 0.340426 (-7395 4557);
PAINT SKYBLUE (-7395 4557);
DISPLAY INVISIBLE (-7395 4557);
FORCEPROP 1 LAST HDL_POWER P3V3_STBY
J 0
(-7650 4475);
DISPLAY 0.872340 (-7650 4475);
PAINT ORANGE (-7650 4475);
DISPLAY INVISIBLE (-7650 4475);
FORCEPROP 1 LAST SIZE 1B
J 0
(-7305 4622);
DISPLAY 0.340426 (-7305 4622);
PAINT GREEN (-7305 4622);
DISPLAY INVISIBLE (-7305 4622);
FORCEPROP 1 LAST PATH I56
J 0
(-7305 4602);
DISPLAY 0.340426 (-7305 4602);
PAINT GREEN (-7305 4602);
DISPLAY INVISIBLE (-7305 4602);
FORCEPROP 2 LAST CDS_LIB mstr_symbols
J 0
(-7350 4600);
PAINT ORANGE (-7350 4600);
DISPLAY INVISIBLE (-7350 4600);
FORCEPROP 1 LAST BODY_TYPE PLUMBING
J 0
(-7395 4557);
DISPLAY 0.340426 (-7395 4557);
PAINT GREEN (-7395 4557);
DISPLAY INVISIBLE (-7395 4557);
FORCEADD RES..2
(-7750 4400);
FORCEPROP 1 LAST LOCATION R7E19
J 0
(-7705 4525);
DISPLAY 0.617021 (-7705 4525);
PAINT AQUA (-7705 4525);
FORCEPROP 1 LAST VALUE 1.00K
J 0
(-7705 4475);
DISPLAY 0.617021 (-7705 4475);
PAINT SKYBLUE (-7705 4475);
FORCEPROP 1 LAST TOLERANCE 1%
J 0
(-7705 4425);
DISPLAY 0.617021 (-7705 4425);
PAINT SKYBLUE (-7705 4425);
FORCEPROP 1 LAST WATTAGE 1/16W
J 0
(-7710 4375);
DISPLAY 0.617021 (-7710 4375);
PAINT SKYBLUE (-7710 4375);
FORCEPROP 1 LAST PACK_TYPE 0402
J 0
(-7710 4225);
DISPLAY 0.617021 (-7710 4225);
PAINT SKYBLUE (-7710 4225);
FORCEPROP 1 LAST PART_NUMBER G21796-026
J 0
(-7710 4275);
DISPLAY 0.617021 (-7710 4275);
PAINT BLUE (-7710 4275);
FORCEPROP 1 LAST MATERIAL EMPTY
J 0
(-7710 4325);
DISPLAY 0.617021 (-7710 4325);
PAINT RED (-7710 4325);
FORCEPROP 1 LASTPIN (-7750 4500) $PN 1
J 0
(-7745 4462);
DISPLAY 0.787234 (-7745 4462);
PAINT ORANGE (-7745 4462);
DISPLAY INVISIBLE (-7745 4462);
FORCEPROP 1 LASTPIN (-7750 4300) $PN 2
J 0
(-7745 4310);
DISPLAY 0.787234 (-7745 4310);
PAINT ORANGE (-7745 4310);
DISPLAY INVISIBLE (-7745 4310);
FORCEPROP 2 LAST ROOM CPLD
J 0
(-7700 4575);
DISPLAY 1.021277 (-7700 4575);
PAINT ORANGE (-7700 4575);
DISPLAY INVISIBLE (-7700 4575);
FORCEPROP 2 LAST $SEC 1
J 0
(-7700 4625);
PAINT MONO (-7700 4625);
DISPLAY INVISIBLE (-7700 4625);
FORCEPROP 2 LAST CDS_SEC 1
J 0
(-7700 4625);
PAINT MONO (-7700 4625);
DISPLAY INVISIBLE (-7700 4625);
FORCEPROP 2 LAST BOM_COST CPLD
J 0
(-7700 4625);
DISPLAY 1.021277 (-7700 4625);
PAINT ORANGE (-7700 4625);
DISPLAY INVISIBLE (-7700 4625);
FORCEPROP 1 LAST PATH I57
J 0
(-7700 4575);
DISPLAY 0.978723 (-7700 4575);
PAINT WHITE (-7700 4575);
DISPLAY INVISIBLE (-7700 4575);
FORCEPROP 2 LAST CDS_LIB mstr_discrete
J 0
(-7750 4400);
PAINT ORANGE (-7750 4400);
DISPLAY INVISIBLE (-7750 4400);
FORCEADD P3V3_STBY..1
(-7750 4600);
FORCEPROP 3 LASTPIN (-7750 4550) SIG_NAME P3V3_STBY\g
J 0
(-7740 4560);
DISPLAY 0.659574 (-7740 4560);
PAINT MONO (-7740 4560);
DISPLAY INVISIBLE (-7740 4560);
FORCEPROP 1 LAST VOLTAGE 3.3V
J 0
(-7795 4557);
DISPLAY 0.340426 (-7795 4557);
PAINT SKYBLUE (-7795 4557);
DISPLAY INVISIBLE (-7795 4557);
FORCEPROP 1 LAST HDL_POWER P3V3_STBY
J 0
(-8050 4475);
DISPLAY 0.872340 (-8050 4475);
PAINT ORANGE (-8050 4475);
DISPLAY INVISIBLE (-8050 4475);
FORCEPROP 1 LAST SIZE 1B
J 0
(-7705 4622);
DISPLAY 0.340426 (-7705 4622);
PAINT GREEN (-7705 4622);
DISPLAY INVISIBLE (-7705 4622);
FORCEPROP 1 LAST PATH I58
J 0
(-7705 4602);
DISPLAY 0.340426 (-7705 4602);
PAINT GREEN (-7705 4602);
DISPLAY INVISIBLE (-7705 4602);
FORCEPROP 2 LAST CDS_LIB mstr_symbols
J 0
(-7750 4600);
PAINT ORANGE (-7750 4600);
DISPLAY INVISIBLE (-7750 4600);
FORCEPROP 1 LAST BODY_TYPE PLUMBING
J 0
(-7795 4557);
DISPLAY 0.340426 (-7795 4557);
PAINT GREEN (-7795 4557);
DISPLAY INVISIBLE (-7795 4557);
FORCEADD RES..2
(-7750 3500);
FORCEPROP 1 LAST LOCATION R7E20
J 0
(-7705 3625);
DISPLAY 0.617021 (-7705 3625);
PAINT AQUA (-7705 3625);
FORCEPROP 1 LAST PART_NUMBER G21796-026
J 0
(-7710 3375);
DISPLAY 0.617021 (-7710 3375);
PAINT BLUE (-7710 3375);
FORCEPROP 1 LAST VALUE 1.00K
J 0
(-7705 3575);
DISPLAY 0.617021 (-7705 3575);
PAINT SKYBLUE (-7705 3575);
FORCEPROP 1 LAST TOLERANCE 1%
J 0
(-7705 3525);
DISPLAY 0.617021 (-7705 3525);
PAINT SKYBLUE (-7705 3525);
FORCEPROP 1 LAST PACK_TYPE 0402
J 0
(-7710 3325);
DISPLAY 0.617021 (-7710 3325);
PAINT SKYBLUE (-7710 3325);
FORCEPROP 1 LAST MATERIAL CHIP
J 0
(-7710 3425);
DISPLAY 0.617021 (-7710 3425);
PAINT SKYBLUE (-7710 3425);
FORCEPROP 1 LAST WATTAGE 1/16W
J 0
(-7710 3475);
DISPLAY 0.617021 (-7710 3475);
PAINT SKYBLUE (-7710 3475);
FORCEPROP 1 LASTPIN (-7750 3600) $PN 1
J 0
(-7745 3562);
DISPLAY 0.787234 (-7745 3562);
PAINT ORANGE (-7745 3562);
DISPLAY INVISIBLE (-7745 3562);
FORCEPROP 1 LASTPIN (-7750 3400) $PN 2
J 0
(-7745 3410);
DISPLAY 0.787234 (-7745 3410);
PAINT ORANGE (-7745 3410);
DISPLAY INVISIBLE (-7745 3410);
FORCEPROP 2 LAST ROOM CPLD
J 0
(-7700 3675);
DISPLAY 1.021277 (-7700 3675);
PAINT ORANGE (-7700 3675);
DISPLAY INVISIBLE (-7700 3675);
FORCEPROP 1 LAST PATH I59
J 0
(-7700 3675);
DISPLAY 0.978723 (-7700 3675);
PAINT WHITE (-7700 3675);
DISPLAY INVISIBLE (-7700 3675);
FORCEPROP 2 LAST $SEC 1
J 0
(-7700 3725);
PAINT MONO (-7700 3725);
DISPLAY INVISIBLE (-7700 3725);
FORCEPROP 2 LAST CDS_SEC 1
J 0
(-7700 3725);
PAINT MONO (-7700 3725);
DISPLAY INVISIBLE (-7700 3725);
FORCEPROP 2 LAST BOM_COST CPLD
J 0
(-7700 3725);
DISPLAY 1.021277 (-7700 3725);
PAINT ORANGE (-7700 3725);
DISPLAY INVISIBLE (-7700 3725);
FORCEPROP 2 LAST CDS_LIB mstr_discrete
J 0
(-7750 3500);
PAINT ORANGE (-7750 3500);
DISPLAY INVISIBLE (-7750 3500);
FORCEADD CAP_A..1
(-2650 1975);
FORCEPROP 1 LAST LOCATION C3P43
J 0
(-2600 2075);
DISPLAY 0.617021 (-2600 2075);
PAINT AQUA (-2600 2075);
FORCEPROP 1 LAST PART_NUMBER A36096-030
J 0
(-2600 1825);
DISPLAY 0.617021 (-2600 1825);
PAINT BLUE (-2600 1825);
FORCEPROP 1 LAST VALUE 0.1UF
J 0
(-2600 2025);
DISPLAY 0.617021 (-2600 2025);
PAINT SKYBLUE (-2600 2025);
FORCEPROP 1 LAST TOLERANCE 10%
J 0
(-2600 1925);
DISPLAY 0.617021 (-2600 1925);
PAINT SKYBLUE (-2600 1925);
FORCEPROP 1 LAST PACK_TYPE 0402V
J 0
(-2600 1775);
DISPLAY 0.617021 (-2600 1775);
PAINT SKYBLUE (-2600 1775);
FORCEPROP 1 LAST VOLTAGE 16V
J 0
(-2600 1975);
DISPLAY 0.617021 (-2600 1975);
PAINT SKYBLUE (-2600 1975);
FORCEPROP 1 LAST MATERIAL X7R
J 0
(-2600 1875);
DISPLAY 0.617021 (-2600 1875);
PAINT SKYBLUE (-2600 1875);
FORCEPROP 1 LASTPIN (-2650 2075) $PN 1
J 0
(-2640 2055);
DISPLAY 0.617021 (-2640 2055);
PAINT ORANGE (-2640 2055);
FORCEPROP 1 LASTPIN (-2650 1875) $PN 2
J 0
(-2640 1855);
DISPLAY 0.617021 (-2640 1855);
PAINT ORANGE (-2640 1855);
FORCEPROP 2 LAST ROOM CPLD
J 0
(-2600 2125);
DISPLAY 1.361702 (-2600 2125);
PAINT ORANGE (-2600 2125);
DISPLAY INVISIBLE (-2600 2125);
FORCEPROP 2 LAST $SEC 1
J 0
(-2600 2175);
PAINT MONO (-2600 2175);
DISPLAY INVISIBLE (-2600 2175);
FORCEPROP 2 LAST CDS_SEC 1
J 0
(-2600 2175);
PAINT MONO (-2600 2175);
DISPLAY INVISIBLE (-2600 2175);
FORCEPROP 2 LAST BOM_COST CPLD
J 0
(-2600 2175);
DISPLAY 1.361702 (-2600 2175);
PAINT ORANGE (-2600 2175);
DISPLAY INVISIBLE (-2600 2175);
FORCEPROP 2 LAST SIGNAL_MODEL DEFAULT_CAPACITOR_100000pF_2_1
J 0
(-2600 2175);
PAINT MONO (-2600 2175);
DISPLAY INVISIBLE (-2600 2175);
FORCEPROP 2 LAST CDS_LOCATION C3P43
J 0
(-2600 2075);
DISPLAY 0.617021 (-2600 2075);
PAINT AQUA (-2600 2075);
DISPLAY INVISIBLE (-2600 2075);
FORCEPROP 1 LAST PATH I6
J 0
(-2600 2125);
DISPLAY 0.978723 (-2600 2125);
PAINT WHITE (-2600 2125);
DISPLAY INVISIBLE (-2600 2125);
FORCEPROP 2 LAST CDS_LIB dev_discrete
J 0
(-2650 1975);
PAINT ORANGE (-2650 1975);
DISPLAY INVISIBLE (-2650 1975);
FORCEADD OFFPAGE..2
(-5100 3700);
FORCEPROP 2 LASTPIN (-5150 3700) SIG_NAME FM_MEM_EVENT_FUNC
J 2
(-5160 3710);
DISPLAY 0.617021 (-5160 3710);
PAINT ORANGE (-5160 3710);
FORCEPROP 2 LAST $XR0 190 
J 0
(-4911 3700);
DISPLAY 0.638298 (-4911 3700);
PAINT MONO (-4911 3700);
FORCEPROP 1 LAST COMMENT_BODY TRUE
J 0
(-5145 3605);
DISPLAY 0.872340 (-5145 3605);
PAINT GREEN (-5145 3605);
DISPLAY INVISIBLE (-5145 3605);
FORCEPROP 1 LAST OFFPAGE TRUE
J 0
(-4775 3575);
DISPLAY 0.872340 (-4775 3575);
PAINT GREEN (-4775 3575);
DISPLAY INVISIBLE (-4775 3575);
FORCEPROP 2 LAST CDS_LIB mstr_standard
J 0
(-5100 3700);
PAINT ORANGE (-5100 3700);
DISPLAY INVISIBLE (-5100 3700);
FORCEPROP 2 LAST PATH I60
J 0
(-4925 3775);
DISPLAY 1.021277 (-4925 3775);
PAINT ORANGE (-4925 3775);
DISPLAY INVISIBLE (-4925 3775);
FORCEADD GND..1
(-7750 3300);
FORCEPROP 3 LASTPIN (-7750 3350) SIG_NAME GND\g
J 0
(-7740 3360);
DISPLAY 0.659574 (-7740 3360);
PAINT MONO (-7740 3360);
DISPLAY INVISIBLE (-7740 3360);
FORCEPROP 1 LAST VOLTAGE 0.0V
J 0
(-7795 3257);
DISPLAY 0.340426 (-7795 3257);
PAINT SKYBLUE (-7795 3257);
DISPLAY INVISIBLE (-7795 3257);
FORCEPROP 1 LAST HDL_POWER GND
J 0
(-7750 3450);
DISPLAY 0.872340 (-7750 3450);
PAINT GREEN (-7750 3450);
DISPLAY INVISIBLE (-7750 3450);
FORCEPROP 1 LAST PATH I61
J 0
(-7675 3300);
DISPLAY 0.872340 (-7675 3300);
PAINT AQUA (-7675 3300);
DISPLAY INVISIBLE (-7675 3300);
FORCEPROP 1 LAST SIZE 1B
J 0
(-7675 3250);
DISPLAY 0.872340 (-7675 3250);
PAINT AQUA (-7675 3250);
DISPLAY INVISIBLE (-7675 3250);
FORCEPROP 2 LAST CDS_LIB mstr_symbols
J 0
(-7750 3300);
PAINT ORANGE (-7750 3300);
DISPLAY INVISIBLE (-7750 3300);
FORCEPROP 1 LAST BODY_TYPE PLUMBING
J 0
(-7795 3257);
DISPLAY 0.340426 (-7795 3257);
PAINT GREEN (-7795 3257);
DISPLAY INVISIBLE (-7795 3257);
FORCEADD PVPP_KLM..1
(-5750 3000);
FORCEPROP 3 LASTPIN (-5750 2950) SIG_NAME PVPP_KLM\g
J 0
(-5740 2960);
DISPLAY 0.659574 (-5740 2960);
PAINT MONO (-5740 2960);
DISPLAY INVISIBLE (-5740 2960);
FORCEPROP 1 LAST VOLTAGE 2.5V
J 0
(-5795 2957);
DISPLAY 0.340426 (-5795 2957);
PAINT SKYBLUE (-5795 2957);
DISPLAY INVISIBLE (-5795 2957);
FORCEPROP 1 LAST HDL_POWER PVPP_KLM
J 1
(-5750 3050);
DISPLAY 0.872340 (-5750 3050);
PAINT GREEN (-5750 3050);
DISPLAY INVISIBLE (-5750 3050);
FORCEPROP 2 LAST ROOM PVPP_KLM_VR
J 0
(-5500 3100);
PAINT ORANGE (-5500 3100);
DISPLAY INVISIBLE (-5500 3100);
FORCEPROP 2 LAST BOM_COST PVPP_KLM_VR
J 0
(-5675 3100);
PAINT MONO (-5675 3100);
DISPLAY INVISIBLE (-5675 3100);
FORCEPROP 1 LAST PATH I62
J 0
(-5700 3025);
DISPLAY 0.872340 (-5700 3025);
PAINT AQUA (-5700 3025);
DISPLAY INVISIBLE (-5700 3025);
FORCEPROP 2 LAST CDS_LIB mstr_symbols
J 0
(-5750 3000);
PAINT ORANGE (-5750 3000);
DISPLAY INVISIBLE (-5750 3000);
FORCEPROP 1 LAST BODY_TYPE PLUMBING
J 0
(-5795 2957);
DISPLAY 0.340426 (-5795 2957);
PAINT GREEN (-5795 2957);
DISPLAY INVISIBLE (-5795 2957);
FORCEADD CAP_A..1
(-3125 1975);
FORCEPROP 1 LAST LOCATION C3R3
J 0
(-3075 2075);
DISPLAY 0.617021 (-3075 2075);
PAINT AQUA (-3075 2075);
FORCEPROP 1 LAST PART_NUMBER A36096-030
J 0
(-3075 1825);
DISPLAY 0.617021 (-3075 1825);
PAINT BLUE (-3075 1825);
FORCEPROP 1 LAST VALUE 0.1UF
J 0
(-3075 2025);
DISPLAY 0.617021 (-3075 2025);
PAINT SKYBLUE (-3075 2025);
FORCEPROP 1 LAST TOLERANCE 10%
J 0
(-3075 1925);
DISPLAY 0.617021 (-3075 1925);
PAINT SKYBLUE (-3075 1925);
FORCEPROP 1 LAST PACK_TYPE 0402V
J 0
(-3075 1775);
DISPLAY 0.617021 (-3075 1775);
PAINT SKYBLUE (-3075 1775);
FORCEPROP 1 LAST VOLTAGE 16V
J 0
(-3075 1975);
DISPLAY 0.617021 (-3075 1975);
PAINT SKYBLUE (-3075 1975);
FORCEPROP 1 LAST MATERIAL X7R
J 0
(-3075 1875);
DISPLAY 0.617021 (-3075 1875);
PAINT SKYBLUE (-3075 1875);
FORCEPROP 1 LASTPIN (-3125 2075) $PN 1
J 0
(-3115 2055);
DISPLAY 0.617021 (-3115 2055);
PAINT ORANGE (-3115 2055);
FORCEPROP 1 LASTPIN (-3125 1875) $PN 2
J 0
(-3115 1855);
DISPLAY 0.617021 (-3115 1855);
PAINT ORANGE (-3115 1855);
FORCEPROP 2 LAST ROOM CPLD
J 0
(-3075 2125);
DISPLAY 1.361702 (-3075 2125);
PAINT ORANGE (-3075 2125);
DISPLAY INVISIBLE (-3075 2125);
FORCEPROP 2 LAST SIGNAL_MODEL DEFAULT_CAPACITOR_100000pF_2_1
J 0
(-3075 2175);
PAINT MONO (-3075 2175);
DISPLAY INVISIBLE (-3075 2175);
FORCEPROP 2 LAST BOM_COST CPLD
J 0
(-3075 2175);
DISPLAY 1.361702 (-3075 2175);
PAINT ORANGE (-3075 2175);
DISPLAY INVISIBLE (-3075 2175);
FORCEPROP 2 LAST CDS_SEC 1
J 0
(-3075 2175);
PAINT MONO (-3075 2175);
DISPLAY INVISIBLE (-3075 2175);
FORCEPROP 2 LAST $SEC 1
J 0
(-3075 2175);
PAINT MONO (-3075 2175);
DISPLAY INVISIBLE (-3075 2175);
FORCEPROP 1 LAST PATH I7
J 0
(-3075 2125);
DISPLAY 0.978723 (-3075 2125);
PAINT WHITE (-3075 2125);
DISPLAY INVISIBLE (-3075 2125);
FORCEPROP 2 LAST CDS_LOCATION C3R3
J 0
(-3075 2075);
DISPLAY 0.617021 (-3075 2075);
PAINT AQUA (-3075 2075);
DISPLAY INVISIBLE (-3075 2075);
FORCEPROP 2 LAST CDS_LIB dev_discrete
J 0
(-3125 1975);
PAINT ORANGE (-3125 1975);
DISPLAY INVISIBLE (-3125 1975);
FORCEADD CAP_A..1
(-3150 1300);
FORCEPROP 1 LAST LOCATION C2R1
J 0
(-3100 1400);
DISPLAY 0.617021 (-3100 1400);
PAINT AQUA (-3100 1400);
FORCEPROP 1 LAST PART_NUMBER A36096-030
J 0
(-3100 1150);
DISPLAY 0.617021 (-3100 1150);
PAINT BLUE (-3100 1150);
FORCEPROP 1 LAST VALUE 0.1UF
J 0
(-3100 1350);
DISPLAY 0.617021 (-3100 1350);
PAINT SKYBLUE (-3100 1350);
FORCEPROP 1 LAST TOLERANCE 10%
J 0
(-3100 1250);
DISPLAY 0.617021 (-3100 1250);
PAINT SKYBLUE (-3100 1250);
FORCEPROP 1 LAST PACK_TYPE 0402V
J 0
(-3100 1100);
DISPLAY 0.617021 (-3100 1100);
PAINT SKYBLUE (-3100 1100);
FORCEPROP 1 LAST VOLTAGE 16V
J 0
(-3100 1300);
DISPLAY 0.617021 (-3100 1300);
PAINT SKYBLUE (-3100 1300);
FORCEPROP 1 LAST MATERIAL X7R
J 0
(-3100 1200);
DISPLAY 0.617021 (-3100 1200);
PAINT SKYBLUE (-3100 1200);
FORCEPROP 1 LASTPIN (-3150 1400) $PN 1
J 0
(-3140 1380);
DISPLAY 0.617021 (-3140 1380);
PAINT ORANGE (-3140 1380);
FORCEPROP 1 LASTPIN (-3150 1200) $PN 2
J 0
(-3140 1180);
DISPLAY 0.617021 (-3140 1180);
PAINT ORANGE (-3140 1180);
FORCEPROP 2 LAST ROOM CPLD
J 0
(-3100 1450);
DISPLAY 1.361702 (-3100 1450);
PAINT ORANGE (-3100 1450);
DISPLAY INVISIBLE (-3100 1450);
FORCEPROP 2 LAST $SEC 1
J 0
(-3100 1500);
DISPLAY 0.914894 (-3100 1500);
PAINT MONO (-3100 1500);
DISPLAY INVISIBLE (-3100 1500);
FORCEPROP 2 LAST CDS_SEC 1
J 0
(-3100 1500);
DISPLAY 1.361702 (-3100 1500);
PAINT ORANGE (-3100 1500);
DISPLAY INVISIBLE (-3100 1500);
FORCEPROP 2 LAST BOM_COST CPLD
J 0
(-3100 1500);
DISPLAY 1.361702 (-3100 1500);
PAINT ORANGE (-3100 1500);
DISPLAY INVISIBLE (-3100 1500);
FORCEPROP 2 LAST SIGNAL_MODEL DEFAULT_CAPACITOR_100000pF_2_1
J 0
(-3100 1500);
PAINT MONO (-3100 1500);
DISPLAY INVISIBLE (-3100 1500);
FORCEPROP 2 LAST CDS_LIB dev_discrete
J 0
(-3150 1300);
PAINT ORANGE (-3150 1300);
DISPLAY INVISIBLE (-3150 1300);
FORCEPROP 2 LAST CDS_LOCATION C2R1
J 0
(-3100 1400);
DISPLAY 0.617021 (-3100 1400);
PAINT AQUA (-3100 1400);
DISPLAY INVISIBLE (-3100 1400);
FORCEPROP 1 LAST PATH I8
J 0
(-3100 1450);
DISPLAY 0.978723 (-3100 1450);
PAINT WHITE (-3100 1450);
DISPLAY INVISIBLE (-3100 1450);
FORCEADD CAP_A..1
(-3600 1975);
FORCEPROP 1 LAST LOCATION C2P2
J 0
(-3550 2075);
DISPLAY 0.617021 (-3550 2075);
PAINT AQUA (-3550 2075);
FORCEPROP 1 LAST PART_NUMBER A36096-030
J 0
(-3550 1825);
DISPLAY 0.617021 (-3550 1825);
PAINT BLUE (-3550 1825);
FORCEPROP 1 LAST VALUE 0.1UF
J 0
(-3550 2025);
DISPLAY 0.617021 (-3550 2025);
PAINT SKYBLUE (-3550 2025);
FORCEPROP 1 LAST TOLERANCE 10%
J 0
(-3550 1925);
DISPLAY 0.617021 (-3550 1925);
PAINT SKYBLUE (-3550 1925);
FORCEPROP 1 LAST PACK_TYPE 0402V
J 0
(-3550 1775);
DISPLAY 0.617021 (-3550 1775);
PAINT SKYBLUE (-3550 1775);
FORCEPROP 1 LAST VOLTAGE 16V
J 0
(-3550 1975);
DISPLAY 0.617021 (-3550 1975);
PAINT SKYBLUE (-3550 1975);
FORCEPROP 1 LAST MATERIAL X7R
J 0
(-3550 1875);
DISPLAY 0.617021 (-3550 1875);
PAINT SKYBLUE (-3550 1875);
FORCEPROP 1 LASTPIN (-3600 2075) $PN 1
J 0
(-3590 2055);
DISPLAY 0.617021 (-3590 2055);
PAINT ORANGE (-3590 2055);
FORCEPROP 1 LASTPIN (-3600 1875) $PN 2
J 0
(-3590 1855);
DISPLAY 0.617021 (-3590 1855);
PAINT ORANGE (-3590 1855);
FORCEPROP 2 LAST ROOM CPLD
J 0
(-3550 2125);
DISPLAY 1.361702 (-3550 2125);
PAINT ORANGE (-3550 2125);
DISPLAY INVISIBLE (-3550 2125);
FORCEPROP 2 LAST $SEC 1
J 0
(-3550 2175);
PAINT MONO (-3550 2175);
DISPLAY INVISIBLE (-3550 2175);
FORCEPROP 2 LAST CDS_SEC 1
J 0
(-3550 2175);
PAINT MONO (-3550 2175);
DISPLAY INVISIBLE (-3550 2175);
FORCEPROP 2 LAST BOM_COST CPLD
J 0
(-3550 2175);
DISPLAY 1.361702 (-3550 2175);
PAINT ORANGE (-3550 2175);
DISPLAY INVISIBLE (-3550 2175);
FORCEPROP 2 LAST SIGNAL_MODEL DEFAULT_CAPACITOR_100000pF_2_1
J 0
(-3550 2175);
PAINT MONO (-3550 2175);
DISPLAY INVISIBLE (-3550 2175);
FORCEPROP 2 LAST CDS_LOCATION C2P2
J 0
(-3550 2075);
DISPLAY 0.617021 (-3550 2075);
PAINT AQUA (-3550 2075);
DISPLAY INVISIBLE (-3550 2075);
FORCEPROP 1 LAST PATH I9
J 0
(-3550 2125);
DISPLAY 0.978723 (-3550 2125);
PAINT WHITE (-3550 2125);
DISPLAY INVISIBLE (-3550 2125);
FORCEPROP 2 LAST CDS_LIB dev_discrete
J 0
(-3600 1975);
PAINT ORANGE (-3600 1975);
DISPLAY INVISIBLE (-3600 1975);
FORCEADD DNS..2
(-7745 4395);
PAINT RED (-7745 4395);
FORCEPROP 2 LAST CDS_LIB mstr_misc
J 0
(-7745 4395);
PAINT ORANGE (-7745 4395);
DISPLAY INVISIBLE (-7745 4395);
FORCEPROP 1 LAST COMMENT_BODY TRUE
R 1
J 0
(-7670 4170);
DISPLAY 0.872340 (-7670 4170);
PAINT GREEN (-7670 4170);
DISPLAY INVISIBLE (-7670 4170);
FORCEADD INTEL_CORP_BPAGE..1
(0 0);
FORCEPROP 1 LAST CDS_CON_LAST_MODIFIED Tue Dec 01 11:52:18 2015
J 0
(-1425 325);
PAINT ORANGE (-1425 325);
DISPLAY INVISIBLE (-1425 325);
FORCEPROP 1 LAST CUSTOM_TXT_CDS <CURRENT_DESIGN_SHEET> OF <TOTAL_DESIGN_SHEETS>
J 0
(-500 25);
PAINT GREEN (-500 25);
FORCEPROP 1 LAST CUSTOM_TXT_CDS <CON_LAST_MODIFIED>
J 0
(-1925 350);
PAINT GREEN (-1925 350);
FORCEPROP 2 LAST CUSTOM_TXT_CDS <XR_PAGE_TITLE>
J 0
(-7890 5250);
DISPLAY 0.638298 (-7890 5250);
PAINT PINK (-7890 5250);
DISPLAY INVISIBLE (-7890 5250);
FORCEPROP 1 LAST SCH_REV 2.420
J 0
(-250 150);
DISPLAY 1.212766 (-250 150);
PAINT YELLOW (-250 150);
FORCEPROP 1 LAST SCH_DEPT BESD
J 1
(-4450 100);
DISPLAY 1.212766 (-4450 100);
PAINT YELLOW (-4450 100);
FORCEPROP 1 LAST SCH_NUMBER H4694802
J 0
(-1300 150);
DISPLAY 1.212766 (-1300 150);
PAINT YELLOW (-1300 150);
FORCEPROP 1 LAST SCH_ADDRESS3 Santa Clara, CA 95052-8119
J 0
(-3975 25);
DISPLAY 0.617021 (-3975 25);
PAINT GREEN (-3975 25);
FORCEPROP 1 LAST SCH_ADDRESS2 P.O. BOX 58119
J 0
(-3975 75);
DISPLAY 0.617021 (-3975 75);
PAINT GREEN (-3975 75);
FORCEPROP 1 LAST SCH_ADDRESS1 2200 Mission College Blvd.
J 0
(-3975 125);
DISPLAY 0.617021 (-3975 125);
PAINT GREEN (-3975 125);
FORCEPROP 1 LAST SCH_TITLE CPLD (3 OF 3)
J 0
(-7950 50);
DISPLAY 1.212766 (-7950 50);
PAINT ORANGE (-7950 50);
FORCEPROP 1 LAST COMMENT_BODY TRUE
J 0
(12 12);
DISPLAY 0.468085 (12 12);
PAINT GREEN (12 12);
DISPLAY INVISIBLE (12 12);
FORCEPROP 2 LAST CDS_LIB mstr_symbols
J 0
(0 0);
PAINT ORANGE (0 0);
DISPLAY INVISIBLE (0 0);
FORCEPROP 2 LAST PAGE_BORDER TRUE
J 0
(-7890 5250);
DISPLAY 0.638298 (-7890 5250);
PAINT PINK (-7890 5250);
DISPLAY INVISIBLE (-7890 5250);
FORCEPROP 2 LAST CDS_XR_PAGE_TITLE CR-192 : @BASEBOARD_FAB2_LIB.BASEBOARD_FAB2(SCH_1):PAGE192
J 0
(-7890 5250);
DISPLAY 0.638298 (-7890 5250);
PAINT PINK (-7890 5250);
DISPLAY INVISIBLE (-7890 5250);
WIRE 16 -1 (-6925 1875)(-6925 1725);
WIRE 16 -1 (-6925 1725)(-6450 1725);
WIRE 16 -1 (-6450 1875)(-6450 1725);
WIRE 16 -1 (-6450 1725)(-5975 1725);
WIRE 16 -1 (-5975 1875)(-5975 1725);
WIRE 16 -1 (-5975 1725)(-5500 1725);
WIRE 16 -1 (-5500 1875)(-5500 1725);
WIRE 16 -1 (-5025 1725)(-5500 1725);
WIRE 16 -1 (-5025 1875)(-5025 1725);
WIRE 16 -1 (-4550 1725)(-5025 1725);
WIRE 16 -1 (-4550 1875)(-4550 1725);
WIRE 16 -1 (-4075 1725)(-4550 1725);
WIRE 16 -1 (-4075 1875)(-4075 1725);
WIRE 16 -1 (-3600 1725)(-4075 1725);
WIRE 16 -1 (-3125 1725)(-3600 1725);
WIRE 16 -1 (-3600 1725)(-3600 1875);
WIRE 16 -1 (-3125 1875)(-3125 1725);
WIRE 16 -1 (-2650 1725)(-3125 1725);
WIRE 16 -1 (-2650 1875)(-2650 1725);
WIRE 16 -1 (-2175 1725)(-2650 1725);
WIRE 16 -1 (-2175 1875)(-2175 1725);
WIRE 16 -1 (-1700 1725)(-2175 1725);
WIRE 16 -1 (-1700 1875)(-1700 1725);
WIRE 16 -1 (-1225 1725)(-1700 1725);
WIRE 16 -1 (-1225 1875)(-1225 1725);
WIRE 16 -1 (-1225 1725)(-1225 1675);
WIRE 16 -1 (-3150 1200)(-3150 1100);
WIRE 16 -1 (-3150 1100)(-3700 1100);
WIRE 16 -1 (-3700 1200)(-3700 1100);
WIRE 16 -1 (-3700 1100)(-4200 1100);
WIRE 16 -1 (-4200 1200)(-4200 1100);
WIRE 16 -1 (-4200 1100)(-4725 1100);
WIRE 16 -1 (-4725 1200)(-4725 1100);
WIRE 16 -1 (-4725 1100)(-5225 1100);
WIRE 16 -1 (-5225 1200)(-5225 1100);
WIRE 16 -1 (-5225 1100)(-5700 1100);
WIRE 16 -1 (-5700 1200)(-5700 1100);
WIRE 16 -1 (-5700 1100)(-6250 1100);
WIRE 16 -1 (-6250 1200)(-6250 1100);
WIRE 16 -1 (-6475 1100)(-6250 1100);
WIRE 16 -1 (-6850 1100)(-6475 1100);
WIRE 16 -1 (-6475 1100)(-6475 1050);
WIRE 16 -1 (-6850 1200)(-6850 1100);
WIRE 16 -1 (-2500 3300)(-2300 3300);
WIRE 16 -1 (-2500 3350)(-2500 3300);
WIRE 16 -1 (-2500 3350)(-2300 3350);
WIRE 16 -1 (-2500 3400)(-2500 3350);
WIRE 16 -1 (-2500 3400)(-2300 3400);
WIRE 16 -1 (-2500 3450)(-2500 3400);
WIRE 16 -1 (-2500 3450)(-2300 3450);
WIRE 16 -1 (-2500 3500)(-2500 3450);
WIRE 16 -1 (-2300 3500)(-2500 3500);
WIRE 16 -1 (-2500 3550)(-2500 3500);
WIRE 16 -1 (-2300 3550)(-2500 3550);
WIRE 16 -1 (-2500 3600)(-2500 3550);
WIRE 16 -1 (-2500 3600)(-2300 3600);
WIRE 16 -1 (-2500 3650)(-2500 3600);
WIRE 16 -1 (-2500 3650)(-2300 3650);
WIRE 16 -1 (-2500 3700)(-2500 3650);
WIRE 16 -1 (-2500 3700)(-2300 3700);
WIRE 16 -1 (-2500 3750)(-2500 3700);
WIRE 16 -1 (-2500 3750)(-2300 3750);
WIRE 16 -1 (-2500 3800)(-2500 3750);
WIRE 16 -1 (-2500 3800)(-2300 3800);
WIRE 16 -1 (-2500 3850)(-2500 3800);
WIRE 16 -1 (-2500 3850)(-2300 3850);
WIRE 16 -1 (-2500 3900)(-2500 3850);
WIRE 16 -1 (-2500 3900)(-2300 3900);
WIRE 16 -1 (-2500 3950)(-2500 3900);
WIRE 16 -1 (-2500 3950)(-2300 3950);
WIRE 16 -1 (-2500 4000)(-2500 3950);
WIRE 16 -1 (-2500 4000)(-2300 4000);
WIRE 16 -1 (-2500 4050)(-2500 4000);
WIRE 16 -1 (-2500 4150)(-2500 4050);
WIRE 16 -1 (-2500 4050)(-2300 4050);
WIRE 16 -1 (-2500 4150)(-2300 4150);
WIRE 16 -1 (-2500 4200)(-2500 4150);
WIRE 16 -1 (-2500 4200)(-2300 4200);
WIRE 16 -1 (-2500 4250)(-2500 4200);
WIRE 16 -1 (-2500 4250)(-2300 4250);
WIRE 16 -1 (-2500 4300)(-2500 4250);
WIRE 16 -1 (-2500 4300)(-2300 4300);
WIRE 16 -1 (-2500 4350)(-2500 4300);
WIRE 16 -1 (-2500 4350)(-2300 4350);
WIRE 16 -1 (-2500 4400)(-2500 4350);
WIRE 16 -1 (-2500 4400)(-2300 4400);
WIRE 16 -1 (-2500 4450)(-2500 4400);
WIRE 16 -1 (-2500 4450)(-2300 4450);
WIRE 16 -1 (-2500 4500)(-2500 4450);
WIRE 16 -1 (-2500 4650)(-2500 4500);
WIRE 16 -1 (-2500 4500)(-2300 4500);
WIRE 16 -1 (-1225 2075)(-1225 2175);
WIRE 16 -1 (-1225 2175)(-1700 2175);
WIRE 16 -1 (-1700 2075)(-1700 2175);
WIRE 16 -1 (-2175 2175)(-1700 2175);
WIRE 16 -1 (-2175 2075)(-2175 2175);
WIRE 16 -1 (-2650 2175)(-2175 2175);
WIRE 16 -1 (-2650 2075)(-2650 2175);
WIRE 16 -1 (-3125 2175)(-2650 2175);
WIRE 16 -1 (-3125 2075)(-3125 2175);
WIRE 16 -1 (-3600 2175)(-3125 2175);
WIRE 16 -1 (-3600 2075)(-3600 2175);
WIRE 16 -1 (-4075 2175)(-3600 2175);
WIRE 16 -1 (-4075 2075)(-4075 2175);
WIRE 16 -1 (-4550 2175)(-4075 2175);
WIRE 16 -1 (-4550 2075)(-4550 2175);
WIRE 16 -1 (-4550 2175)(-5025 2175);
WIRE 16 -1 (-5025 2075)(-5025 2175);
WIRE 16 -1 (-5500 2175)(-5025 2175);
WIRE 16 -1 (-5500 2075)(-5500 2175);
WIRE 16 -1 (-5975 2175)(-5500 2175);
WIRE 16 -1 (-5975 2075)(-5975 2175);
WIRE 16 -1 (-6450 2175)(-5975 2175);
WIRE 16 -1 (-6450 2075)(-6450 2175);
WIRE 16 -1 (-6925 2175)(-6450 2175);
WIRE 16 -1 (-6925 2075)(-6925 2175);
WIRE 16 -1 (-6925 2225)(-6925 2175);
WIRE 16 -1 (-3150 1400)(-3150 1450);
WIRE 16 -1 (-3150 1450)(-3700 1450);
WIRE 16 -1 (-3700 1400)(-3700 1450);
WIRE 16 -1 (-3700 1450)(-4200 1450);
WIRE 16 -1 (-4200 1400)(-4200 1450);
WIRE 16 -1 (-4200 1450)(-4725 1450);
WIRE 16 -1 (-4725 1400)(-4725 1450);
WIRE 16 -1 (-4725 1450)(-5225 1450);
WIRE 16 -1 (-5225 1400)(-5225 1450);
WIRE 16 -1 (-5225 1450)(-5700 1450);
WIRE 16 -1 (-5700 1400)(-5700 1450);
WIRE 16 -1 (-5700 1450)(-6250 1450);
WIRE 16 -1 (-6250 1400)(-6250 1450);
WIRE 16 -1 (-6850 1450)(-6250 1450);
WIRE 16 -1 (-6850 1400)(-6850 1450);
WIRE 16 -1 (-6850 1475)(-6850 1450);
WIRE 16 -1 (-6150 4500)(-6150 4550);
WIRE 16 -1 (-5750 4550)(-5750 4500);
WIRE 16 -1 (-6550 4500)(-6550 4550);
WIRE 16 -1 (-6950 4500)(-6950 4550);
WIRE 16 -1 (-1100 4400)(-1100 4350);
WIRE 16 -1 (-1100 4400)(-1400 4400);
WIRE 16 -1 (-1100 4350)(-1100 4300);
WIRE 16 -1 (-1100 4350)(-1400 4350);
WIRE 16 -1 (-1100 4300)(-1100 4250);
WIRE 16 -1 (-1100 4300)(-1400 4300);
WIRE 16 -1 (-1100 4250)(-1100 4200);
WIRE 16 -1 (-1100 4250)(-1400 4250);
WIRE 16 -1 (-1400 4200)(-1100 4200);
WIRE 16 -1 (-1100 4200)(-1100 4150);
WIRE 16 -1 (-1100 4150)(-1100 4100);
WIRE 16 -1 (-1100 4150)(-1400 4150);
WIRE 16 -1 (-1100 4100)(-1400 4100);
WIRE 16 -1 (-1100 4100)(-1100 4050);
WIRE 16 -1 (-1100 4050)(-1100 4000);
WIRE 16 -1 (-1100 4050)(-1400 4050);
WIRE 16 -1 (-1100 4000)(-1100 3950);
WIRE 16 -1 (-1100 4000)(-1400 4000);
WIRE 16 -1 (-1100 3950)(-1100 3900);
WIRE 16 -1 (-1100 3950)(-1400 3950);
WIRE 16 -1 (-1100 3900)(-1100 3850);
WIRE 16 -1 (-1100 3900)(-1400 3900);
WIRE 16 -1 (-1100 3850)(-1100 3800);
WIRE 16 -1 (-1100 3850)(-1400 3850);
WIRE 16 -1 (-1100 3800)(-1100 3750);
WIRE 16 -1 (-1100 3800)(-1400 3800);
WIRE 16 -1 (-1100 3750)(-1100 3700);
WIRE 16 -1 (-1100 3750)(-1400 3750);
WIRE 16 -1 (-1100 3700)(-1100 3650);
WIRE 16 -1 (-1100 3700)(-1400 3700);
WIRE 16 -1 (-1100 3650)(-1100 3600);
WIRE 16 -1 (-1100 3650)(-1400 3650);
WIRE 16 -1 (-1100 3600)(-1400 3600);
WIRE 16 -1 (-1100 3600)(-1100 3550);
WIRE 16 -1 (-1100 3550)(-1100 3500);
WIRE 16 -1 (-1100 3550)(-1400 3550);
WIRE 16 -1 (-1100 3500)(-1100 3450);
WIRE 16 -1 (-1100 3500)(-1400 3500);
WIRE 16 -1 (-1100 3450)(-1100 3400);
WIRE 16 -1 (-1100 3450)(-1400 3450);
WIRE 16 -1 (-1100 3400)(-1100 3350);
WIRE 16 -1 (-1100 3400)(-1400 3400);
WIRE 16 -1 (-1100 3350)(-1100 3300);
WIRE 16 -1 (-1100 3350)(-1400 3350);
WIRE 16 -1 (-1100 3300)(-1100 3250);
WIRE 16 -1 (-1100 3300)(-1400 3300);
WIRE 16 -1 (-1100 3250)(-1100 3150);
WIRE 16 -1 (-1100 3250)(-1400 3250);
WIRE 16 -1 (-6150 2950)(-6150 2900);
WIRE 16 -1 (-7350 4550)(-7350 4500);
WIRE 16 -1 (-7750 4500)(-7750 4550);
WIRE 16 -1 (-7750 3400)(-7750 3350);
WIRE 16 -1 (-5750 2950)(-5750 2900);
WIRE 16 273 (-4700 3300)(-4700 3550);
WIRE 16 273 (-7400 3300)(-4700 3300);
WIRE 16 273 (-4700 3550)(-7400 3550);
WIRE 16 273 (-7400 3550)(-7400 3300);
WIRE 16 -1 (-6150 2500)(-5150 2500);
WIRE 16 -1 (-6150 2700)(-6150 2500);
WIRE 16 -1 (-5750 2600)(-5150 2600);
WIRE 16 -1 (-5750 2700)(-5750 2600);
WIRE 16 -1 (-7750 4300)(-7750 3700);
WIRE 16 -1 (-7750 3700)(-5150 3700);
WIRE 16 -1 (-7750 3700)(-7750 3600);
WIRE 16 -1 (-6950 4300)(-6950 3900);
WIRE 16 -1 (-6950 3900)(-5150 3900);
WIRE 16 -1 (-7350 3800)(-7350 4300);
WIRE 16 -1 (-5150 3800)(-7350 3800);
WIRE 16 -1 (-6550 4300)(-6550 4000);
WIRE 16 -1 (-6550 4000)(-5150 4000);
WIRE 16 -1 (-6150 4100)(-5150 4100);
WIRE 16 -1 (-6150 4300)(-6150 4100);
WIRE 16 -1 (-5750 4200)(-5150 4200);
WIRE 16 -1 (-5750 4300)(-5750 4200);
WIRE 16 -1 (-950 4550)(-1400 4550);
FORCEPROP 0 LAST SIG_NAME NC_CPLD1
J 0
(-1285 4560);
DISPLAY 0.617021 (-1285 4560);
PAINT ORANGE (-1285 4560);
FORCEPROP 2 LASTPROP $XRERR UNIQUE?
J 0
(-920 4550);
DISPLAY 0.638298 (-920 4550);
PAINT MONO (-920 4550);
DISPLAY INVISIBLE (-920 4550);
DOT 1 (-6850 1450);
DOT 1 (-6475 1100);
DOT 1 (-6250 1100);
DOT 1 (-6250 1450);
DOT 1 (-6450 1725);
DOT 1 (-7750 3700);
DOT 1 (-6925 2175);
DOT 1 (-6450 2175);
DOT 1 (-5700 1100);
DOT 1 (-5700 1450);
DOT 1 (-5975 1725);
DOT 1 (-5225 1100);
DOT 1 (-5225 1450);
DOT 1 (-5500 1725);
DOT 1 (-4725 1100);
DOT 1 (-4725 1450);
DOT 1 (-5025 1725);
DOT 1 (-4200 1100);
DOT 1 (-4200 1450);
DOT 1 (-4550 1725);
DOT 1 (-5975 2175);
DOT 1 (-5500 2175);
DOT 1 (-5025 2175);
DOT 1 (-4550 2175);
DOT 1 (-3700 1100);
DOT 1 (-3700 1450);
DOT 1 (-4075 1725);
DOT 1 (-3600 1725);
DOT 1 (-3125 1725);
DOT 1 (-2650 1725);
DOT 1 (-2175 1725);
DOT 1 (-4075 2175);
DOT 1 (-3600 2175);
DOT 1 (-3125 2175);
DOT 1 (-2650 2175);
DOT 1 (-2175 2175);
DOT 1 (-2500 3350);
DOT 1 (-2500 3400);
DOT 1 (-2500 3450);
DOT 1 (-2500 3500);
DOT 1 (-2500 3550);
DOT 1 (-2500 3600);
DOT 1 (-2500 3650);
DOT 1 (-2500 3700);
DOT 1 (-2500 3750);
DOT 1 (-2500 3800);
DOT 1 (-2500 3850);
DOT 1 (-2500 3950);
DOT 1 (-2500 3900);
DOT 1 (-2500 4000);
DOT 1 (-2500 4050);
DOT 1 (-1700 1725);
DOT 1 (-1225 1725);
DOT 1 (-1700 2175);
DOT 1 (-1100 3250);
DOT 1 (-1100 3300);
DOT 1 (-1100 3350);
DOT 1 (-1100 3400);
DOT 1 (-1100 3450);
DOT 1 (-1100 3550);
DOT 1 (-1100 3500);
DOT 1 (-1100 3600);
DOT 1 (-1100 3700);
DOT 1 (-1100 3650);
DOT 1 (-1100 3750);
DOT 1 (-1100 3800);
DOT 1 (-1100 3850);
DOT 1 (-1100 3900);
DOT 1 (-1100 3950);
DOT 1 (-1100 4000);
DOT 1 (-1100 4050);
DOT 1 (-1100 4100);
DOT 1 (-2500 4150);
DOT 1 (-2500 4200);
DOT 1 (-2500 4250);
DOT 1 (-2500 4300);
DOT 1 (-2500 4350);
DOT 1 (-2500 4450);
DOT 1 (-2500 4400);
DOT 1 (-2500 4500);
DOT 1 (-1100 4200);
DOT 1 (-1100 4150);
DOT 1 (-1100 4300);
DOT 1 (-1100 4350);
DOT 1 (-1100 4250);
FORCENOTE
HIGH:  MEM_EVENT ASSERTION ASSERTS THERMTRIP TO PCH THROUGH CPLD
(-7350 3325) 0;
DISPLAY LEFT (-7350 3325);
DISPLAY 0.851064 (-7350 3325);
PAINT PURPLE (-7350 3325);
FORCENOTE
LOW:    MEM_EVENT ASSERTION DOES NOT DRIVE THERMTRIP (NVDIMM MODE)
(-7350 3400) 0;
DISPLAY LEFT (-7350 3400);
DISPLAY 0.851064 (-7350 3400);
PAINT PURPLE (-7350 3400);
FORCENOTE
FM_MEM_EVENT_FUNC STATE:
(-7350 3475) 0;
DISPLAY LEFT (-7350 3475);
DISPLAY 0.851064 (-7350 3475);
PAINT PURPLE (-7350 3475);
FORCENOTE
ROOM CPLD
(-7875 425) 0;
DISPLAY LEFT (-7875 425);
DISPLAY 2.148936 (-7875 425);
PAINT PURPLE (-7875 425);
FORCENOTE
BOM_COST CPLD
(-7900 300) 0;
DISPLAY LEFT (-7900 300);
DISPLAY 2.148936 (-7900 300);
PAINT PURPLE (-7900 300);
QUIT
